(lib_symbols
	(symbol "TP_0.75mm_SMD_1"
			(pin_numbers
				(hide yes)
			)
			(pin_names
				(hide yes)
			)
			(exclude_from_sim no)
			(in_bom yes)
			(on_board yes)
			(property "Reference" "TP"
				(at 17.78 -5.08 0)
				(effects
					(font
						(size 1.27 1.27)
						(thickness 0.15)
					)
					(justify left bottom)
				)
			)
			(property "Value" "TP_0.75mm_SMD_1"
				(at 17.78 -7.62 0)
				(effects
					(font
						(size 1.27 1.27)
						(thickness 0.15)
					)
					(justify left bottom)
					(hide yes)
				)
			)
			(property "Footprint" "lpddr4-testbed-footprints:TP_SMD_0.75mm"
				(at 17.78 -10.16 0)
				(effects
					(font
						(size 1.27 1.27)
						(thickness 0.15)
					)
					(justify left bottom)
					(hide yes)
				)
			)
			(property "Datasheet" ""
				(at 17.78 -12.7 0)
				(effects
					(font
						(size 1.27 1.27)
						(thickness 0.15)
					)
					(justify left bottom)
					(hide yes)
				)
			)
			(property "Description" "Test Point 0.75mm"
				(at 0 0 0)
				(effects
					(font
						(size 1.27 1.27)
					)
					(hide yes)
				)
			)
			(property "MPN" ""
				(at 17.78 -15.24 0)
				(effects
					(font
						(size 1.27 1.27)
						(thickness 0.15)
					)
					(justify left bottom)
					(hide yes)
				)
			)
			(property "Manufacturer" ""
				(at 17.78 -17.78 0)
				(effects
					(font
						(size 1.27 1.27)
						(thickness 0.15)
					)
					(justify left bottom)
					(hide yes)
				)
			)
			(property "Author" "Antmicro"
				(at 17.78 -20.32 0)
				(effects
					(font
						(size 1.27 1.27)
						(thickness 0.15)
					)
					(justify left bottom)
					(hide yes)
				)
			)
			(property "License" "Apache-2.0"
				(at 17.78 -22.86 0)
				(effects
					(font
						(size 1.27 1.27)
						(thickness 0.15)
					)
					(justify left bottom)
					(hide yes)
				)
			)
			(symbol "TP_0.75mm_SMD_1_1_1"
				(circle
					(center 3.175 0)
					(radius 0.635)
					(stroke
						(width 0.254)
						(type default)
					)
					(fill
						(type none)
					)
				)
				(pin passive line
					(at 0 0 0)
					(length 2.54)
					(name "1"
						(effects
							(font
								(size 1.27 1.27)
							)
						)
					)
					(number "1"
						(effects
							(font
								(size 1.27 1.27)
							)
						)
					)
				)
			)
		)
	(symbol "TP_0.75mm_SMD_2"
			(pin_numbers
				(hide yes)
			)
			(pin_names
				(hide yes)
			)
			(exclude_from_sim no)
			(in_bom yes)
			(on_board yes)
			(property "Reference" "TP"
				(at 17.78 -5.08 0)
				(effects
					(font
						(size 1.27 1.27)
						(thickness 0.15)
					)
					(justify left bottom)
				)
			)
			(property "Value" "TP_0.75mm_SMD_2"
				(at 17.78 -7.62 0)
				(effects
					(font
						(size 1.27 1.27)
						(thickness 0.15)
					)
					(justify left bottom)
					(hide yes)
				)
			)
			(property "Footprint" "lpddr4-testbed-footprints:TP_SMD_0.75mm"
				(at 17.78 -10.16 0)
				(effects
					(font
						(size 1.27 1.27)
						(thickness 0.15)
					)
					(justify left bottom)
					(hide yes)
				)
			)
			(property "Datasheet" ""
				(at 17.78 -12.7 0)
				(effects
					(font
						(size 1.27 1.27)
						(thickness 0.15)
					)
					(justify left bottom)
					(hide yes)
				)
			)
			(property "Description" "Test Point 0.75mm"
				(at 0 0 0)
				(effects
					(font
						(size 1.27 1.27)
					)
					(hide yes)
				)
			)
			(property "MPN" ""
				(at 17.78 -15.24 0)
				(effects
					(font
						(size 1.27 1.27)
						(thickness 0.15)
					)
					(justify left bottom)
					(hide yes)
				)
			)
			(property "Manufacturer" ""
				(at 17.78 -17.78 0)
				(effects
					(font
						(size 1.27 1.27)
						(thickness 0.15)
					)
					(justify left bottom)
					(hide yes)
				)
			)
			(property "Author" "Antmicro"
				(at 17.78 -20.32 0)
				(effects
					(font
						(size 1.27 1.27)
						(thickness 0.15)
					)
					(justify left bottom)
					(hide yes)
				)
			)
			(property "License" "Apache-2.0"
				(at 17.78 -22.86 0)
				(effects
					(font
						(size 1.27 1.27)
						(thickness 0.15)
					)
					(justify left bottom)
					(hide yes)
				)
			)
			(symbol "TP_0.75mm_SMD_2_1_1"
				(circle
					(center 3.175 0)
					(radius 0.635)
					(stroke
						(width 0.254)
						(type default)
					)
					(fill
						(type none)
					)
				)
				(pin passive line
					(at 0 0 0)
					(length 2.54)
					(name "1"
						(effects
							(font
								(size 1.27 1.27)
							)
						)
					)
					(number "1"
						(effects
							(font
								(size 1.27 1.27)
							)
						)
					)
				)
			)
		)
	(symbol "antmicroCapacitors0402:C_100n_0402"
			(pin_numbers
				(hide yes)
			)
			(pin_names
				(hide yes)
			)
			(exclude_from_sim no)
			(in_bom yes)
			(on_board yes)
			(property "Reference" "C"
				(at 20.32 -5.08 0)
				(effects
					(font
						(size 1.27 1.27)
						(thickness 0.15)
					)
					(justify left bottom)
				)
			)
			(property "Value" "C_100n_0402"
				(at 20.32 -10.16 0)
				(effects
					(font
						(size 1.27 1.27)
						(thickness 0.15)
					)
					(justify left bottom)
					(hide yes)
				)
			)
			(property "Footprint" "antmicro-footprints:C_0402_1005Metric"
				(at 20.32 -12.7 0)
				(effects
					(font
						(size 1.27 1.27)
						(thickness 0.15)
					)
					(justify left bottom)
					(hide yes)
				)
			)
			(property "Datasheet" "https://search.murata.co.jp/Ceramy/image/img/A01X/G101/ENG/GRM155R61H104KE14-01.pdf"
				(at 20.32 -15.24 0)
				(effects
					(font
						(size 1.27 1.27)
						(thickness 0.15)
					)
					(justify left bottom)
					(hide yes)
				)
			)
			(property "Description" ""
				(at 0 0 0)
				(effects
					(font
						(size 1.27 1.27)
					)
					(hide yes)
				)
			)
			(property "MPN" "GRM155R61H104KE14D"
				(at 20.32 -17.78 0)
				(effects
					(font
						(size 1.27 1.27)
						(thickness 0.15)
					)
					(justify left bottom)
					(hide yes)
				)
			)
			(property "Manufacturer" "Murata"
				(at 20.32 -20.32 0)
				(effects
					(font
						(size 1.27 1.27)
						(thickness 0.15)
					)
					(justify left bottom)
					(hide yes)
				)
			)
			(property "License" "Apache-2.0"
				(at 20.32 -22.86 0)
				(effects
					(font
						(size 1.27 1.27)
						(thickness 0.15)
					)
					(justify left bottom)
					(hide yes)
				)
			)
			(property "Author" "Antmicro"
				(at 20.32 -25.4 0)
				(effects
					(font
						(size 1.27 1.27)
						(thickness 0.15)
					)
					(justify left bottom)
					(hide yes)
				)
			)
			(property "Val" "100n"
				(at 20.32 -7.62 0)
				(effects
					(font
						(size 1.27 1.27)
						(thickness 0.15)
					)
					(justify left bottom)
				)
			)
			(property "Voltage" "50V"
				(at 20.32 -27.94 0)
				(effects
					(font
						(size 1.27 1.27)
					)
					(justify left bottom)
					(hide yes)
				)
			)
			(property "Dielectric" "X5R"
				(at 20.32 -30.48 0)
				(effects
					(font
						(size 1.27 1.27)
					)
					(justify left bottom)
					(hide yes)
				)
			)
			(symbol "C_100n_0402_0_1"
				(polyline
					(pts
						(xy 2.032 -1.524) (xy 2.032 1.524)
					)
					(stroke
						(width 0.3048)
						(type default)
					)
					(fill
						(type none)
					)
				)
				(polyline
					(pts
						(xy 3.048 -1.524) (xy 3.048 1.524)
					)
					(stroke
						(width 0.3302)
						(type default)
					)
					(fill
						(type none)
					)
				)
			)
			(symbol "C_100n_0402_1_1"
				(pin passive line
					(at 0 0 0)
					(length 2.032)
					(name "~"
						(effects
							(font
								(size 1.27 1.27)
							)
						)
					)
					(number "1"
						(effects
							(font
								(size 1.27 1.27)
							)
						)
					)
				)
				(pin passive line
					(at 5.08 0 180)
					(length 2.032)
					(name "~"
						(effects
							(font
								(size 1.27 1.27)
							)
						)
					)
					(number "2"
						(effects
							(font
								(size 1.27 1.27)
							)
						)
					)
				)
			)
		)
	(symbol "antmicroCapacitors0402:C_4u7_0402"
			(pin_numbers
				(hide yes)
			)
			(pin_names
				(hide yes)
			)
			(exclude_from_sim no)
			(in_bom yes)
			(on_board yes)
			(property "Reference" "C"
				(at 20.32 -5.08 0)
				(effects
					(font
						(size 1.27 1.27)
						(thickness 0.15)
					)
					(justify left bottom)
				)
			)
			(property "Value" "C_4u7_0402"
				(at 20.32 -10.16 0)
				(effects
					(font
						(size 1.27 1.27)
						(thickness 0.15)
					)
					(justify left bottom)
					(hide yes)
				)
			)
			(property "Footprint" "antmicro-footprints:C_0402_1005Metric"
				(at 20.32 -12.7 0)
				(effects
					(font
						(size 1.27 1.27)
						(thickness 0.15)
					)
					(justify left bottom)
					(hide yes)
				)
			)
			(property "Datasheet" ""
				(at 20.32 -15.24 0)
				(effects
					(font
						(size 1.27 1.27)
						(thickness 0.15)
					)
					(justify left bottom)
					(hide yes)
				)
			)
			(property "Description" ""
				(at 0 0 0)
				(effects
					(font
						(size 1.27 1.27)
					)
					(hide yes)
				)
			)
			(property "MPN" "GRM155R61A475MEAAD"
				(at 20.32 -17.78 0)
				(effects
					(font
						(size 1.27 1.27)
						(thickness 0.15)
					)
					(justify left bottom)
					(hide yes)
				)
			)
			(property "Manufacturer" "Murata"
				(at 20.32 -20.32 0)
				(effects
					(font
						(size 1.27 1.27)
						(thickness 0.15)
					)
					(justify left bottom)
					(hide yes)
				)
			)
			(property "License" "Apache-2.0"
				(at 20.32 -22.86 0)
				(effects
					(font
						(size 1.27 1.27)
						(thickness 0.15)
					)
					(justify left bottom)
					(hide yes)
				)
			)
			(property "Author" "Antmicro"
				(at 20.32 -25.4 0)
				(effects
					(font
						(size 1.27 1.27)
						(thickness 0.15)
					)
					(justify left bottom)
					(hide yes)
				)
			)
			(property "Val" "4u7"
				(at 20.32 -7.62 0)
				(effects
					(font
						(size 1.27 1.27)
						(thickness 0.15)
					)
					(justify left bottom)
				)
			)
			(property "Voltage" ""
				(at 20.32 -27.94 0)
				(effects
					(font
						(size 1.27 1.27)
					)
					(justify left bottom)
					(hide yes)
				)
			)
			(property "Dielectric" ""
				(at 20.32 -30.48 0)
				(effects
					(font
						(size 1.27 1.27)
					)
					(justify left bottom)
					(hide yes)
				)
			)
			(symbol "C_4u7_0402_0_1"
				(polyline
					(pts
						(xy 2.032 -1.524) (xy 2.032 1.524)
					)
					(stroke
						(width 0.3048)
						(type default)
					)
					(fill
						(type none)
					)
				)
				(polyline
					(pts
						(xy 3.048 -1.524) (xy 3.048 1.524)
					)
					(stroke
						(width 0.3302)
						(type default)
					)
					(fill
						(type none)
					)
				)
			)
			(symbol "C_4u7_0402_1_1"
				(pin passive line
					(at 0 0 0)
					(length 2.032)
					(name "~"
						(effects
							(font
								(size 1.27 1.27)
							)
						)
					)
					(number "1"
						(effects
							(font
								(size 1.27 1.27)
							)
						)
					)
				)
				(pin passive line
					(at 5.08 0 180)
					(length 2.032)
					(name "~"
						(effects
							(font
								(size 1.27 1.27)
							)
						)
					)
					(number "2"
						(effects
							(font
								(size 1.27 1.27)
							)
						)
					)
				)
			)
		)
	(symbol "antmicroCapacitorsmisc:C_100n_0201"
			(pin_numbers
				(hide yes)
			)
			(pin_names
				(hide yes)
			)
			(exclude_from_sim no)
			(in_bom yes)
			(on_board yes)
			(property "Reference" "C"
				(at 20.32 -5.08 0)
				(effects
					(font
						(size 1.27 1.27)
						(thickness 0.15)
					)
					(justify left bottom)
				)
			)
			(property "Value" "C_100n_0201_34"
				(at 20.32 -10.16 0)
				(effects
					(font
						(size 1.27 1.27)
						(thickness 0.15)
					)
					(justify left bottom)
					(hide yes)
				)
			)
			(property "Footprint" "antmicro-footprints:C_0201"
				(at 20.32 -12.7 0)
				(effects
					(font
						(size 1.27 1.27)
						(thickness 0.15)
					)
					(justify left bottom)
					(hide yes)
				)
			)
			(property "Datasheet" ""
				(at 20.32 -15.24 0)
				(effects
					(font
						(size 1.27 1.27)
						(thickness 0.15)
					)
					(justify left bottom)
					(hide yes)
				)
			)
			(property "Description" ""
				(at 0 0 0)
				(effects
					(font
						(size 1.27 1.27)
					)
					(hide yes)
				)
			)
			(property "MPN" "CC0201KRX6S5BB104"
				(at 20.32 -17.78 0)
				(effects
					(font
						(size 1.27 1.27)
						(thickness 0.15)
					)
					(justify left bottom)
					(hide yes)
				)
			)
			(property "Manufacturer" "Yaego"
				(at 20.32 -20.32 0)
				(effects
					(font
						(size 1.27 1.27)
						(thickness 0.15)
					)
					(justify left bottom)
					(hide yes)
				)
			)
			(property "License" "Apache-2.0"
				(at 20.32 -22.86 0)
				(effects
					(font
						(size 1.27 1.27)
						(thickness 0.15)
					)
					(justify left bottom)
					(hide yes)
				)
			)
			(property "Author" "Antmicro"
				(at 20.32 -25.4 0)
				(effects
					(font
						(size 1.27 1.27)
						(thickness 0.15)
					)
					(justify left bottom)
					(hide yes)
				)
			)
			(property "Val" "100n"
				(at 20.32 -7.62 0)
				(effects
					(font
						(size 1.27 1.27)
						(thickness 0.15)
					)
					(justify left bottom)
				)
			)
			(property "Voltage" ""
				(at 20.32 -27.94 0)
				(effects
					(font
						(size 1.27 1.27)
					)
					(justify left bottom)
					(hide yes)
				)
			)
			(property "Dielectric" ""
				(at 20.32 -30.48 0)
				(effects
					(font
						(size 1.27 1.27)
					)
					(justify left bottom)
					(hide yes)
				)
			)
			(symbol "C_100n_0201_0_1"
				(polyline
					(pts
						(xy 2.032 -1.524) (xy 2.032 1.524)
					)
					(stroke
						(width 0.3048)
						(type default)
					)
					(fill
						(type none)
					)
				)
				(polyline
					(pts
						(xy 3.048 -1.524) (xy 3.048 1.524)
					)
					(stroke
						(width 0.3302)
						(type default)
					)
					(fill
						(type none)
					)
				)
			)
			(symbol "C_100n_0201_1_1"
				(pin passive line
					(at 0 0 0)
					(length 2.032)
					(name "~"
						(effects
							(font
								(size 1.27 1.27)
							)
						)
					)
					(number "1"
						(effects
							(font
								(size 1.27 1.27)
							)
						)
					)
				)
				(pin passive line
					(at 5.08 0 180)
					(length 2.032)
					(name "~"
						(effects
							(font
								(size 1.27 1.27)
							)
						)
					)
					(number "2"
						(effects
							(font
								(size 1.27 1.27)
							)
						)
					)
				)
			)
		)
	(symbol "antmicroDCDCConverters:TPS613221A_SOT-23-5"
			(exclude_from_sim no)
			(in_bom yes)
			(on_board yes)
			(property "Reference" "U"
				(at 33.02 -2.54 0)
				(effects
					(font
						(size 1.27 1.27)
						(thickness 0.15)
					)
					(justify left bottom)
				)
			)
			(property "Value" "TPS613221A_SOT-23-5"
				(at 33.02 -5.08 0)
				(effects
					(font
						(size 1.27 1.27)
						(thickness 0.15)
					)
					(justify left bottom)
				)
			)
			(property "Footprint" "antmicro-footprints:SOT-23-5"
				(at 33.02 -7.62 0)
				(effects
					(font
						(size 1.27 1.27)
						(thickness 0.15)
					)
					(justify left bottom)
					(hide yes)
				)
			)
			(property "Datasheet" "https://www.ti.com/lit/ds/symlink/tps61322.pdf?ts=1679307661323&ref_url=https%253A%252F%252Fwww.ti.com%252Fproduct%252FTPS61322%252Fpart-details%252FTPS613221ADBVT%253Futm_source%253Dgoogle%2526utm_medium%253Dcpc%2526utm_campaign%253Docb-tistore-promo-app_opn_en-cpc-storeic-google-wwe%2526utm_content%253DDevice%2526ds_k%253DTPS613221ADBVT%2526DCM%253Dyes%2526gclid%253DCjwKCAjwiOCgBhAgEiwAjv5whAbq73RvnAdgvLpW8LFuSFEla1kNqoJei2y0mTqS4-Xlc-1KWPDvLxoCIUoQAvD_BwE%2526gclsrc%253Daw.ds"
				(at 33.02 -10.16 0)
				(effects
					(font
						(size 1.27 1.27)
						(thickness 0.15)
					)
					(justify left bottom)
					(hide yes)
				)
			)
			(property "Description" "1.8-A switch current boost converter 6.5-μA Quiescent current"
				(at 0 0 0)
				(effects
					(font
						(size 1.27 1.27)
					)
					(hide yes)
				)
			)
			(property "Manufacturer" "Texas Instruments"
				(at 33.02 -12.7 0)
				(effects
					(font
						(size 1.27 1.27)
						(thickness 0.15)
					)
					(justify left bottom)
					(hide yes)
				)
			)
			(property "MPN" "TPS613221ADBVT"
				(at 33.02 -15.24 0)
				(effects
					(font
						(size 1.27 1.27)
						(thickness 0.15)
					)
					(justify left bottom)
					(hide yes)
				)
			)
			(property "Author" "Antmicro"
				(at 33.02 -17.78 0)
				(effects
					(font
						(size 1.27 1.27)
						(thickness 0.15)
					)
					(justify left bottom)
					(hide yes)
				)
			)
			(property "License" "Apache-2.0"
				(at 33.02 -20.32 0)
				(effects
					(font
						(size 1.27 1.27)
						(thickness 0.15)
					)
					(justify left bottom)
					(hide yes)
				)
			)
			(property "ki_keywords" "1.8-A switch current boost converter 6.5-μA Quiescent current"
				(at 0 0 0)
				(effects
					(font
						(size 1.27 1.27)
					)
					(hide yes)
				)
			)
			(property "ki_fp_filters" "DBV0005A_N DBV0005A_M DBV0005A_L"
				(at 0 0 0)
				(effects
					(font
						(size 1.27 1.27)
					)
					(hide yes)
				)
			)
			(symbol "TPS613221A_SOT-23-5_1_1"
				(rectangle
					(start 2.54 2.54)
					(end 12.7 -7.62)
					(stroke
						(width 0.254)
						(type default)
					)
					(fill
						(type background)
					)
				)
				(rectangle
					(start 12.7 -7.62)
					(end 12.7 -7.62)
					(stroke
						(width 0.254)
						(type default)
					)
					(fill
						(type background)
					)
				)
				(pin power_in line
					(at 0 0 0)
					(length 2.54)
					(name "SW"
						(effects
							(font
								(size 1.27 1.27)
							)
						)
					)
					(number "1"
						(effects
							(font
								(size 1.27 1.27)
							)
						)
					)
				)
				(pin no_connect line
					(at 2.54 -2.54 0)
					(length 2.54)
					(hide yes)
					(name "NC"
						(effects
							(font
								(size 1.27 1.27)
							)
						)
					)
					(number "3"
						(effects
							(font
								(size 1.27 1.27)
							)
						)
					)
				)
				(pin no_connect line
					(at 2.54 -5.08 0)
					(length 2.54)
					(hide yes)
					(name "NC"
						(effects
							(font
								(size 1.27 1.27)
							)
						)
					)
					(number "5"
						(effects
							(font
								(size 1.27 1.27)
							)
						)
					)
				)
				(pin power_in line
					(at 15.24 0 180)
					(length 2.54)
					(name "VOUT"
						(effects
							(font
								(size 1.27 1.27)
							)
						)
					)
					(number "4"
						(effects
							(font
								(size 1.27 1.27)
							)
						)
					)
				)
				(pin power_in line
					(at 15.24 -5.08 180)
					(length 2.54)
					(name "GND"
						(effects
							(font
								(size 1.27 1.27)
							)
						)
					)
					(number "2"
						(effects
							(font
								(size 1.27 1.27)
							)
						)
					)
				)
			)
		)
	(symbol "antmicroFixedInductors:L_2u2_1.5A_0806"
			(pin_numbers
				(hide yes)
			)
			(pin_names
				(hide yes)
			)
			(exclude_from_sim no)
			(in_bom yes)
			(on_board yes)
			(property "Reference" "L"
				(at 13.97 0 0)
				(effects
					(font
						(size 1.27 1.27)
						(thickness 0.15)
					)
					(justify left bottom)
				)
			)
			(property "Value" "L_2u2_1.5A_1285AS-H"
				(at 13.97 -2.54 0)
				(effects
					(font
						(size 1.27 1.27)
						(thickness 0.15)
					)
					(justify left bottom)
					(hide yes)
				)
			)
			(property "Footprint" "antmicro-footprints:L_0806_2016Metric"
				(at 13.97 -7.62 0)
				(effects
					(font
						(size 1.27 1.27)
						(thickness 0.15)
					)
					(justify left bottom)
					(hide yes)
				)
			)
			(property "Datasheet" "https://search.murata.co.jp/Ceramy/image/img/P02/J(E)TE243A-0011.pdf"
				(at 13.97 -10.16 0)
				(effects
					(font
						(size 1.27 1.27)
						(thickness 0.15)
					)
					(justify left bottom)
					(hide yes)
				)
			)
			(property "Description" ""
				(at 0 0 0)
				(effects
					(font
						(size 1.27 1.27)
					)
					(hide yes)
				)
			)
			(property "Val" "2u2/1.5A"
				(at 13.97 -5.08 0)
				(effects
					(font
						(size 1.27 1.27)
					)
					(justify left bottom)
				)
			)
			(property "Manufacturer" "Murata"
				(at 13.97 -12.7 0)
				(effects
					(font
						(size 1.27 1.27)
					)
					(justify left bottom)
					(hide yes)
				)
			)
			(property "MPN" "1285AS-H-2R2M=P2"
				(at 13.97 -15.24 0)
				(effects
					(font
						(size 1.27 1.27)
					)
					(justify left bottom)
					(hide yes)
				)
			)
			(property "ISat" ""
				(at 13.97 -16.51 0)
				(effects
					(font
						(size 1.27 1.27)
					)
					(justify left)
					(hide yes)
				)
			)
			(property "Isat" "1.2A"
				(at 13.97 -17.78 0)
				(effects
					(font
						(size 1.27 1.27)
					)
					(justify left bottom)
					(hide yes)
				)
			)
			(property "IMax" ""
				(at 13.97 -20.32 0)
				(effects
					(font
						(size 1.27 1.27)
						(thickness 0.15)
					)
					(justify left bottom)
					(hide yes)
				)
			)
			(property "Imax" "1.5A"
				(at 13.97 -20.32 0)
				(effects
					(font
						(size 1.27 1.27)
					)
					(justify left bottom)
					(hide yes)
				)
			)
			(property "Size" "0806_2016Metric"
				(at 13.97 -22.86 0)
				(effects
					(font
						(size 1.27 1.27)
					)
					(justify left bottom)
					(hide yes)
				)
			)
			(property "Author" "Antmicro"
				(at 13.97 -25.4 0)
				(effects
					(font
						(size 1.27 1.27)
					)
					(justify left bottom)
					(hide yes)
				)
			)
			(property "License" "Apache-2.0"
				(at 13.97 -27.94 0)
				(effects
					(font
						(size 1.27 1.27)
					)
					(justify left bottom)
					(hide yes)
				)
			)
			(symbol "L_2u2_1.5A_0806_0_1"
				(arc
					(start 0.508 0)
					(mid 1.016 0.5058)
					(end 1.524 0)
					(stroke
						(width 0)
						(type default)
					)
					(fill
						(type none)
					)
				)
				(arc
					(start 1.524 0)
					(mid 2.032 0.5058)
					(end 2.54 0)
					(stroke
						(width 0)
						(type default)
					)
					(fill
						(type none)
					)
				)
				(arc
					(start 2.54 0)
					(mid 3.048 0.5058)
					(end 3.556 0)
					(stroke
						(width 0)
						(type default)
					)
					(fill
						(type none)
					)
				)
				(arc
					(start 3.556 0)
					(mid 4.064 0.5058)
					(end 4.572 0)
					(stroke
						(width 0)
						(type default)
					)
					(fill
						(type none)
					)
				)
			)
			(symbol "L_2u2_1.5A_0806_1_1"
				(pin passive line
					(at 0 0 0)
					(length 0.508)
					(name "~"
						(effects
							(font
								(size 1.27 1.27)
							)
						)
					)
					(number "1"
						(effects
							(font
								(size 1.27 1.27)
							)
						)
					)
				)
				(pin passive line
					(at 5.08 0 180)
					(length 0.508)
					(name "~"
						(effects
							(font
								(size 1.27 1.27)
							)
						)
					)
					(number "2"
						(effects
							(font
								(size 1.27 1.27)
							)
						)
					)
				)
			)
		)
	(symbol "antmicroInterfaceIOExpanders:PCA6408A_TSSOP"
			(exclude_from_sim no)
			(in_bom yes)
			(on_board yes)
			(property "Reference" "U"
				(at 35.56 -2.54 0)
				(effects
					(font
						(size 1.27 1.27)
						(thickness 0.15)
					)
					(justify left bottom)
				)
			)
			(property "Value" "PCA6408A_TSSOP"
				(at 35.56 -5.08 0)
				(effects
					(font
						(size 1.27 1.27)
						(thickness 0.15)
					)
					(justify left bottom)
				)
			)
			(property "Footprint" "antmicro-footprints:TSSOP-16_4.4x5mm_P0.65mm"
				(at 35.56 -7.62 0)
				(effects
					(font
						(size 1.27 1.27)
						(thickness 0.15)
					)
					(justify left bottom)
					(hide yes)
				)
			)
			(property "Datasheet" "https://www.mouser.pl/datasheet/2/302/PCA6408A-1127604.pdf"
				(at 35.56 -10.16 0)
				(effects
					(font
						(size 1.27 1.27)
						(thickness 0.15)
					)
					(justify left bottom)
					(hide yes)
				)
			)
			(property "Description" "Low-voltage, 8-bit I2C-bus and SMBus I/O expander"
				(at 0 0 0)
				(effects
					(font
						(size 1.27 1.27)
					)
					(hide yes)
				)
			)
			(property "Manufacturer" "NXP"
				(at 35.56 -12.7 0)
				(effects
					(font
						(size 1.27 1.27)
						(thickness 0.15)
					)
					(justify left bottom)
					(hide yes)
				)
			)
			(property "MPN" "PCA6408APW"
				(at 35.56 -15.24 0)
				(effects
					(font
						(size 1.27 1.27)
						(thickness 0.15)
					)
					(justify left bottom)
					(hide yes)
				)
			)
			(property "Author" "Antmicro"
				(at 35.56 -17.78 0)
				(effects
					(font
						(size 1.27 1.27)
						(thickness 0.15)
					)
					(justify left bottom)
					(hide yes)
				)
			)
			(property "License" "Apache-2.0"
				(at 35.56 -20.32 0)
				(effects
					(font
						(size 1.27 1.27)
						(thickness 0.15)
					)
					(justify left bottom)
					(hide yes)
				)
			)
			(symbol "PCA6408A_TSSOP_1_1"
				(rectangle
					(start 2.54 2.54)
					(end 19.05 -27.94)
					(stroke
						(width 0.254)
						(type default)
					)
					(fill
						(type background)
					)
				)
				(pin power_in line
					(at 0 0 0)
					(length 2.54)
					(name "VDD(P)"
						(effects
							(font
								(size 1.27 1.27)
							)
						)
					)
					(number "16"
						(effects
							(font
								(size 1.27 1.27)
							)
						)
					)
				)
				(pin power_in line
					(at 0 -2.54 0)
					(length 2.54)
					(name "VDD(I2C)"
						(effects
							(font
								(size 1.27 1.27)
							)
						)
					)
					(number "1"
						(effects
							(font
								(size 1.27 1.27)
							)
						)
					)
				)
				(pin open_collector line
					(at 0 -7.62 0)
					(length 2.54)
					(name "SDA"
						(effects
							(font
								(size 1.27 1.27)
							)
						)
					)
					(number "15"
						(effects
							(font
								(size 1.27 1.27)
							)
						)
					)
				)
				(pin open_collector line
					(at 0 -10.16 0)
					(length 2.54)
					(name "SCL"
						(effects
							(font
								(size 1.27 1.27)
							)
						)
					)
					(number "14"
						(effects
							(font
								(size 1.27 1.27)
							)
						)
					)
				)
				(pin open_collector line
					(at 0 -15.24 0)
					(length 2.54)
					(name "~{INT}"
						(effects
							(font
								(size 1.27 1.27)
							)
						)
					)
					(number "13"
						(effects
							(font
								(size 1.27 1.27)
							)
						)
					)
				)
				(pin input line
					(at 0 -17.78 0)
					(length 2.54)
					(name "~{RESET}"
						(effects
							(font
								(size 1.27 1.27)
							)
						)
					)
					(number "3"
						(effects
							(font
								(size 1.27 1.27)
							)
						)
					)
				)
				(pin input line
					(at 0 -20.32 0)
					(length 2.54)
					(name "ADDR"
						(effects
							(font
								(size 1.27 1.27)
							)
						)
					)
					(number "2"
						(effects
							(font
								(size 1.27 1.27)
							)
						)
					)
				)
				(pin power_in line
					(at 0 -25.4 0)
					(length 2.54)
					(name "GND"
						(effects
							(font
								(size 1.27 1.27)
							)
						)
					)
					(number "8"
						(effects
							(font
								(size 1.27 1.27)
							)
						)
					)
				)
				(pin bidirectional line
					(at 21.59 0 180)
					(length 2.54)
					(name "P0"
						(effects
							(font
								(size 1.27 1.27)
							)
						)
					)
					(number "4"
						(effects
							(font
								(size 1.27 1.27)
							)
						)
					)
				)
				(pin bidirectional line
					(at 21.59 -2.54 180)
					(length 2.54)
					(name "P1"
						(effects
							(font
								(size 1.27 1.27)
							)
						)
					)
					(number "5"
						(effects
							(font
								(size 1.27 1.27)
							)
						)
					)
				)
				(pin bidirectional line
					(at 21.59 -5.08 180)
					(length 2.54)
					(name "P2"
						(effects
							(font
								(size 1.27 1.27)
							)
						)
					)
					(number "6"
						(effects
							(font
								(size 1.27 1.27)
							)
						)
					)
				)
				(pin bidirectional line
					(at 21.59 -7.62 180)
					(length 2.54)
					(name "P3"
						(effects
							(font
								(size 1.27 1.27)
							)
						)
					)
					(number "7"
						(effects
							(font
								(size 1.27 1.27)
							)
						)
					)
				)
				(pin bidirectional line
					(at 21.59 -12.7 180)
					(length 2.54)
					(name "P4"
						(effects
							(font
								(size 1.27 1.27)
							)
						)
					)
					(number "9"
						(effects
							(font
								(size 1.27 1.27)
							)
						)
					)
				)
				(pin bidirectional line
					(at 21.59 -15.24 180)
					(length 2.54)
					(name "P5"
						(effects
							(font
								(size 1.27 1.27)
							)
						)
					)
					(number "10"
						(effects
							(font
								(size 1.27 1.27)
							)
						)
					)
				)
				(pin bidirectional line
					(at 21.59 -17.78 180)
					(length 2.54)
					(name "P6"
						(effects
							(font
								(size 1.27 1.27)
							)
						)
					)
					(number "11"
						(effects
							(font
								(size 1.27 1.27)
							)
						)
					)
				)
				(pin bidirectional line
					(at 21.59 -20.32 180)
					(length 2.54)
					(name "P7"
						(effects
							(font
								(size 1.27 1.27)
							)
						)
					)
					(number "12"
						(effects
							(font
								(size 1.27 1.27)
							)
						)
					)
				)
			)
		)
	(symbol "antmicroLEDIndicationDiscrete:LED_G_0603_KP-1608CGCK"
			(pin_names
				(hide yes)
			)
			(exclude_from_sim no)
			(in_bom yes)
			(on_board yes)
			(property "Reference" "D"
				(at 22.86 -5.08 0)
				(effects
					(font
						(size 1.27 1.27)
						(thickness 0.15)
					)
					(justify left bottom)
				)
			)
			(property "Value" "LED_G_0603_KP-1608CGCK"
				(at 22.86 -7.62 0)
				(effects
					(font
						(size 1.27 1.27)
						(thickness 0.15)
					)
					(justify left bottom)
				)
			)
			(property "Footprint" "antmicro-footprints:LED_0603_1608Metric_G"
				(at 22.86 -10.16 0)
				(effects
					(font
						(size 1.27 1.27)
						(thickness 0.15)
					)
					(justify left bottom)
					(hide yes)
				)
			)
			(property "Datasheet" "http://www.farnell.com/datasheets/2045956.pdf"
				(at 22.86 -12.7 0)
				(effects
					(font
						(size 1.27 1.27)
						(thickness 0.15)
					)
					(justify left bottom)
					(hide yes)
				)
			)
			(property "Description" ""
				(at 0 0 0)
				(effects
					(font
						(size 1.27 1.27)
					)
					(hide yes)
				)
			)
			(property "MPN" "KP-1608CGCK"
				(at 22.86 -15.24 0)
				(effects
					(font
						(size 1.27 1.27)
						(thickness 0.15)
					)
					(justify left bottom)
					(hide yes)
				)
			)
			(property "Manufacturer" "Kingbright"
				(at 22.86 -17.78 0)
				(effects
					(font
						(size 1.27 1.27)
						(thickness 0.15)
					)
					(justify left bottom)
					(hide yes)
				)
			)
			(property "Author" "Antmicro"
				(at 22.86 -20.32 0)
				(effects
					(font
						(size 1.27 1.27)
						(thickness 0.15)
					)
					(justify left bottom)
					(hide yes)
				)
			)
			(property "License" "Apache-2.0"
				(at 22.86 -22.86 0)
				(effects
					(font
						(size 1.27 1.27)
						(thickness 0.15)
					)
					(justify left bottom)
					(hide yes)
				)
			)
			(symbol "LED_G_0603_KP-1608CGCK_1_1"
				(polyline
					(pts
						(xy 2.54 1.27) (xy 2.54 -1.27) (xy 5.08 0) (xy 2.54 1.27)
					)
					(stroke
						(width 0.254)
						(type default)
					)
					(fill
						(type outline)
					)
				)
				(polyline
					(pts
						(xy 3.683 2.286) (xy 3.683 1.778) (xy 3.683 2.286) (xy 3.175 2.286) (xy 3.683 2.286) (xy 2.794 1.397)
					)
					(stroke
						(width 0.254)
						(type default)
					)
					(fill
						(type none)
					)
				)
				(polyline
					(pts
						(xy 4.699 2.032) (xy 4.699 1.524) (xy 4.699 2.032) (xy 4.191 2.032) (xy 4.699 2.032) (xy 3.683 1.016)
					)
					(stroke
						(width 0.254)
						(type default)
					)
					(fill
						(type none)
					)
				)
				(polyline
					(pts
						(xy 5.08 1.27) (xy 5.08 -1.27)
					)
					(stroke
						(width 0.254)
						(type default)
					)
					(fill
						(type none)
					)
				)
				(pin passive line
					(at 0 0 0)
					(length 2.54)
					(name "1"
						(effects
							(font
								(size 1.27 1.27)
							)
						)
					)
					(number "1"
						(effects
							(font
								(size 1.27 1.27)
							)
						)
					)
				)
				(pin passive line
					(at 7.62 0 180)
					(length 2.54)
					(name "2"
						(effects
							(font
								(size 1.27 1.27)
							)
						)
					)
					(number "2"
						(effects
							(font
								(size 1.27 1.27)
							)
						)
					)
				)
			)
		)
	(symbol "antmicroMemory:AT24CS01_SOT23"
			(exclude_from_sim no)
			(in_bom yes)
			(on_board yes)
			(property "Reference" "U"
				(at 35.56 -2.54 0)
				(effects
					(font
						(size 1.27 1.27)
						(thickness 0.15)
					)
					(justify left bottom)
				)
			)
			(property "Value" "AT24CS01_SOT23"
				(at 35.56 -5.08 0)
				(effects
					(font
						(size 1.27 1.27)
						(thickness 0.15)
					)
					(justify left bottom)
				)
			)
			(property "Footprint" "antmicro-footprints:SOT-23-5"
				(at 35.56 -7.62 0)
				(effects
					(font
						(size 1.27 1.27)
						(thickness 0.15)
					)
					(justify left bottom)
					(hide yes)
				)
			)
			(property "Datasheet" "http://ww1.microchip.com/downloads/en/devicedoc/Atmel-8815-SEEPROM-AT24CS01-02-Datasheet.pdf"
				(at 35.56 -10.16 0)
				(effects
					(font
						(size 1.27 1.27)
						(thickness 0.15)
					)
					(justify left bottom)
					(hide yes)
				)
			)
			(property "Description" "SOT-23-5"
				(at 0 0 0)
				(effects
					(font
						(size 1.27 1.27)
					)
					(hide yes)
				)
			)
			(property "Manufacturer" "Atmel"
				(at 35.56 -12.7 0)
				(effects
					(font
						(size 1.27 1.27)
						(thickness 0.15)
					)
					(justify left bottom)
					(hide yes)
				)
			)
			(property "MPN" "AT24CS01-ST"
				(at 35.56 -15.24 0)
				(effects
					(font
						(size 1.27 1.27)
						(thickness 0.15)
					)
					(justify left bottom)
					(hide yes)
				)
			)
			(property "Author" "Antmicro"
				(at 35.56 -17.78 0)
				(effects
					(font
						(size 1.27 1.27)
						(thickness 0.15)
					)
					(justify left bottom)
					(hide yes)
				)
			)
			(property "License" "Apache-2.0"
				(at 35.56 -20.32 0)
				(effects
					(font
						(size 1.27 1.27)
						(thickness 0.15)
					)
					(justify left bottom)
					(hide yes)
				)
			)
			(property "ki_keywords" "SOT-23-5"
				(at 0 0 0)
				(effects
					(font
						(size 1.27 1.27)
					)
					(hide yes)
				)
			)
			(symbol "AT24CS01_SOT23_1_1"
				(rectangle
					(start 2.54 -7.62)
					(end 17.78 2.54)
					(stroke
						(width 0.254)
						(type default)
					)
					(fill
						(type background)
					)
				)
				(pin passive line
					(at 0 0 0)
					(length 2.54)
					(name "SDA"
						(effects
							(font
								(size 1.27 1.27)
							)
						)
					)
					(number "3"
						(effects
							(font
								(size 1.27 1.27)
							)
						)
					)
				)
				(pin passive line
					(at 0 -2.54 0)
					(length 2.54)
					(name "SCL"
						(effects
							(font
								(size 1.27 1.27)
							)
						)
					)
					(number "1"
						(effects
							(font
								(size 1.27 1.27)
							)
						)
					)
				)
				(pin passive line
					(at 0 -5.08 0)
					(length 2.54)
					(name "WP"
						(effects
							(font
								(size 1.27 1.27)
							)
						)
					)
					(number "5"
						(effects
							(font
								(size 1.27 1.27)
							)
						)
					)
				)
				(pin passive line
					(at 20.32 0 180)
					(length 2.54)
					(name "VCC"
						(effects
							(font
								(size 1.27 1.27)
							)
						)
					)
					(number "4"
						(effects
							(font
								(size 1.27 1.27)
							)
						)
					)
				)
				(pin passive line
					(at 20.32 -2.54 180)
					(length 2.54)
					(name "GND"
						(effects
							(font
								(size 1.27 1.27)
							)
						)
					)
					(number "2"
						(effects
							(font
								(size 1.27 1.27)
							)
						)
					)
				)
			)
		)
	(symbol "antmicroMemory:MT53E1G32D2NP-046"
			(exclude_from_sim no)
			(in_bom yes)
			(on_board yes)
			(property "Reference" "U"
				(at 55.88 0 0)
				(effects
					(font
						(size 1.27 1.27)
						(thickness 0.15)
					)
					(justify left bottom)
				)
			)
			(property "Value" "MT53E1G32D2NP-046"
				(at 55.88 -2.54 0)
				(effects
					(font
						(size 1.27 1.27)
						(thickness 0.15)
					)
					(justify left bottom)
				)
			)
			(property "Footprint" "antmicro-footprints:BGA-264-200_10x14.5mm_Layout12x22_P0.8x0.65mm"
				(at 55.88 -5.08 0)
				(effects
					(font
						(size 1.27 1.27)
						(thickness 0.15)
					)
					(justify left bottom)
					(hide yes)
				)
			)
			(property "Datasheet" "https://www.micron.com/products/dram/lpdram/part-catalog/mt53e1g32d2np-046-wt"
				(at 55.88 -7.62 0)
				(effects
					(font
						(size 1.27 1.27)
						(thickness 0.15)
					)
					(justify left bottom)
					(hide yes)
				)
			)
			(property "Description" "DRAM, Mobile LPDDR4, 32 Gbit, 1G x 32bit, 2.133 GHz, WFBGA, 200 Pins"
				(at 0 0 0)
				(effects
					(font
						(size 1.27 1.27)
					)
					(hide yes)
				)
			)
			(property "Manufacturer" "Micron Technology"
				(at 55.88 -10.16 0)
				(effects
					(font
						(size 1.27 1.27)
						(thickness 0.15)
					)
					(justify left bottom)
					(hide yes)
				)
			)
			(property "MPN" "MT53E1G32D2NP-046 WT:A"
				(at 55.88 -12.7 0)
				(effects
					(font
						(size 1.27 1.27)
						(thickness 0.15)
					)
					(justify left bottom)
					(hide yes)
				)
			)
			(property "Author" "Antmicro"
				(at 55.88 -15.24 0)
				(effects
					(font
						(size 1.27 1.27)
						(thickness 0.15)
					)
					(justify left bottom)
					(hide yes)
				)
			)
			(property "License" "Apache-2.0"
				(at 55.88 -17.78 0)
				(effects
					(font
						(size 1.27 1.27)
						(thickness 0.15)
					)
					(justify left bottom)
					(hide yes)
				)
			)
			(property "ki_locked" ""
				(at 0 0 0)
				(effects
					(font
						(size 1.27 1.27)
					)
				)
			)
			(property "ki_keywords" "SMT, DRAM, IC"
				(at 0 0 0)
				(effects
					(font
						(size 1.27 1.27)
					)
					(hide yes)
				)
			)
			(property "ki_fp_filters" "BGA*10.0x14.5mm*P0.80x0.65mm*"
				(at 0 0 0)
				(effects
					(font
						(size 1.27 1.27)
					)
					(hide yes)
				)
			)
			(symbol "MT53E1G32D2NP-046_1_1"
				(rectangle
					(start 5.08 2.54)
					(end 35.56 -60.96)
					(stroke
						(width 0.254)
						(type default)
					)
					(fill
						(type background)
					)
				)
				(pin power_in line
					(at 0 0 0)
					(length 5.08)
					(name "VDDQ"
						(effects
							(font
								(size 1.27 1.27)
							)
						)
					)
					(number "B10"
						(effects
							(font
								(size 1.27 1.27)
							)
						)
					)
				)
				(pin passive line
					(at 0 0 0)
					(length 5.08)
					(hide yes)
					(name "VDDQ"
						(effects
							(font
								(size 1.27 1.27)
							)
						)
					)
					(number "B3"
						(effects
							(font
								(size 1.27 1.27)
							)
						)
					)
				)
				(pin passive line
					(at 0 0 0)
					(length 5.08)
					(hide yes)
					(name "VDDQ"
						(effects
							(font
								(size 1.27 1.27)
							)
						)
					)
					(number "B5"
						(effects
							(font
								(size 1.27 1.27)
							)
						)
					)
				)
				(pin passive line
					(at 0 0 0)
					(length 5.08)
					(hide yes)
					(name "VDDQ"
						(effects
							(font
								(size 1.27 1.27)
							)
						)
					)
					(number "B8"
						(effects
							(font
								(size 1.27 1.27)
							)
						)
					)
				)
				(pin passive line
					(at 0 0 0)
					(length 5.08)
					(hide yes)
					(name "VDDQ"
						(effects
							(font
								(size 1.27 1.27)
							)
						)
					)
					(number "D1"
						(effects
							(font
								(size 1.27 1.27)
							)
						)
					)
				)
				(pin passive line
					(at 0 0 0)
					(length 5.08)
					(hide yes)
					(name "VDDQ"
						(effects
							(font
								(size 1.27 1.27)
							)
						)
					)
					(number "D12"
						(effects
							(font
								(size 1.27 1.27)
							)
						)
					)
				)
				(pin passive line
					(at 0 0 0)
					(length 5.08)
					(hide yes)
					(name "VDDQ"
						(effects
							(font
								(size 1.27 1.27)
							)
						)
					)
					(number "D5"
						(effects
							(font
								(size 1.27 1.27)
							)
						)
					)
				)
				(pin passive line
					(at 0 0 0)
					(length 5.08)
					(hide yes)
					(name "VDDQ"
						(effects
							(font
								(size 1.27 1.27)
							)
						)
					)
					(number "D8"
						(effects
							(font
								(size 1.27 1.27)
							)
						)
					)
				)
				(pin passive line
					(at 0 0 0)
					(length 5.08)
					(hide yes)
					(name "VDDQ"
						(effects
							(font
								(size 1.27 1.27)
							)
						)
					)
					(number "F10"
						(effects
							(font
								(size 1.27 1.27)
							)
						)
					)
				)
				(pin passive line
					(at 0 0 0)
					(length 5.08)
					(hide yes)
					(name "VDDQ"
						(effects
							(font
								(size 1.27 1.27)
							)
						)
					)
					(number "F3"
						(effects
							(font
								(size 1.27 1.27)
							)
						)
					)
				)
				(pin input line
					(at 0 -2.54 0)
					(length 5.08)
					(name "RESET_N"
						(effects
							(font
								(size 1.27 1.27)
							)
						)
					)
					(number "T11"
						(effects
							(font
								(size 1.27 1.27)
							)
						)
					)
				)
				(pin power_in line
					(at 0 -7.62 0)
					(length 5.08)
					(name "VDD1"
						(effects
							(font
								(size 1.27 1.27)
							)
						)
					)
					(number "F1"
						(effects
							(font
								(size 1.27 1.27)
							)
						)
					)
				)
				(pin passive line
					(at 0 -7.62 0)
					(length 5.08)
					(hide yes)
					(name "VDD1"
						(effects
							(font
								(size 1.27 1.27)
							)
						)
					)
					(number "F12"
						(effects
							(font
								(size 1.27 1.27)
							)
						)
					)
				)
				(pin passive line
					(at 0 -7.62 0)
					(length 5.08)
					(hide yes)
					(name "VDD1"
						(effects
							(font
								(size 1.27 1.27)
							)
						)
					)
					(number "G4"
						(effects
							(font
								(size 1.27 1.27)
							)
						)
					)
				)
				(pin passive line
					(at 0 -7.62 0)
					(length 5.08)
					(hide yes)
					(name "VDD1"
						(effects
							(font
								(size 1.27 1.27)
							)
						)
					)
					(number "G9"
						(effects
							(font
								(size 1.27 1.27)
							)
						)
					)
				)
				(pin power_in line
					(at 0 -10.16 0)
					(length 5.08)
					(name "VDD2"
						(effects
							(font
								(size 1.27 1.27)
							)
						)
					)
					(number "A4"
						(effects
							(font
								(size 1.27 1.27)
							)
						)
					)
				)
				(pin passive line
					(at 0 -10.16 0)
					(length 5.08)
					(hide yes)
					(name "VDD2"
						(effects
							(font
								(size 1.27 1.27)
							)
						)
					)
					(number "A9"
						(effects
							(font
								(size 1.27 1.27)
							)
						)
					)
				)
				(pin passive line
					(at 0 -10.16 0)
					(length 5.08)
					(hide yes)
					(name "VDD2"
						(effects
							(font
								(size 1.27 1.27)
							)
						)
					)
					(number "F5"
						(effects
							(font
								(size 1.27 1.27)
							)
						)
					)
				)
				(pin passive line
					(at 0 -10.16 0)
					(length 5.08)
					(hide yes)
					(name "VDD2"
						(effects
							(font
								(size 1.27 1.27)
							)
						)
					)
					(number "F8"
						(effects
							(font
								(size 1.27 1.27)
							)
						)
					)
				)
				(pin passive line
					(at 0 -10.16 0)
					(length 5.08)
					(hide yes)
					(name "VDD2"
						(effects
							(font
								(size 1.27 1.27)
							)
						)
					)
					(number "H1"
						(effects
							(font
								(size 1.27 1.27)
							)
						)
					)
				)
				(pin passive line
					(at 0 -10.16 0)
					(length 5.08)
					(hide yes)
					(name "VDD2"
						(effects
							(font
								(size 1.27 1.27)
							)
						)
					)
					(number "H12"
						(effects
							(font
								(size 1.27 1.27)
							)
						)
					)
				)
				(pin passive line
					(at 0 -10.16 0)
					(length 5.08)
					(hide yes)
					(name "VDD2"
						(effects
							(font
								(size 1.27 1.27)
							)
						)
					)
					(number "H5"
						(effects
							(font
								(size 1.27 1.27)
							)
						)
					)
				)
				(pin passive line
					(at 0 -10.16 0)
					(length 5.08)
					(hide yes)
					(name "VDD2"
						(effects
							(font
								(size 1.27 1.27)
							)
						)
					)
					(number "H8"
						(effects
							(font
								(size 1.27 1.27)
							)
						)
					)
				)
				(pin passive line
					(at 0 -10.16 0)
					(length 5.08)
					(hide yes)
					(name "VDD2"
						(effects
							(font
								(size 1.27 1.27)
							)
						)
					)
					(number "K1"
						(effects
							(font
								(size 1.27 1.27)
							)
						)
					)
				)
				(pin passive line
					(at 0 -10.16 0)
					(length 5.08)
					(hide yes)
					(name "VDD2"
						(effects
							(font
								(size 1.27 1.27)
							)
						)
					)
					(number "K10"
						(effects
							(font
								(size 1.27 1.27)
							)
						)
					)
				)
				(pin passive line
					(at 0 -10.16 0)
					(length 5.08)
					(hide yes)
					(name "VDD2"
						(effects
							(font
								(size 1.27 1.27)
							)
						)
					)
					(number "K12"
						(effects
							(font
								(size 1.27 1.27)
							)
						)
					)
				)
				(pin passive line
					(at 0 -10.16 0)
					(length 5.08)
					(hide yes)
					(name "VDD2"
						(effects
							(font
								(size 1.27 1.27)
							)
						)
					)
					(number "K3"
						(effects
							(font
								(size 1.27 1.27)
							)
						)
					)
				)
				(pin input line
					(at 0 -15.24 0)
					(length 5.08)
					(name "CK_T_A"
						(effects
							(font
								(size 1.27 1.27)
							)
						)
					)
					(number "J8"
						(effects
							(font
								(size 1.27 1.27)
							)
						)
					)
				)
				(pin input line
					(at 0 -17.78 0)
					(length 5.08)
					(name "CK_C_A"
						(effects
							(font
								(size 1.27 1.27)
							)
						)
					)
					(number "J9"
						(effects
							(font
								(size 1.27 1.27)
							)
						)
					)
				)
				(pin input line
					(at 0 -20.32 0)
					(length 5.08)
					(name "CS0_A"
						(effects
							(font
								(size 1.27 1.27)
							)
						)
					)
					(number "H4"
						(effects
							(font
								(size 1.27 1.27)
							)
						)
					)
				)
				(pin input line
					(at 0 -27.94 0)
					(length 5.08)
					(name "CA0_A"
						(effects
							(font
								(size 1.27 1.27)
							)
						)
					)
					(number "H2"
						(effects
							(font
								(size 1.27 1.27)
							)
						)
					)
				)
				(pin input line
					(at 0 -30.48 0)
					(length 5.08)
					(name "CA1_A"
						(effects
							(font
								(size 1.27 1.27)
							)
						)
					)
					(number "J2"
						(effects
							(font
								(size 1.27 1.27)
							)
						)
					)
				)
				(pin input line
					(at 0 -33.02 0)
					(length 5.08)
					(name "CA2_A"
						(effects
							(font
								(size 1.27 1.27)
							)
						)
					)
					(number "H9"
						(effects
							(font
								(size 1.27 1.27)
							)
						)
					)
				)
				(pin input line
					(at 0 -35.56 0)
					(length 5.08)
					(name "CA3_A"
						(effects
							(font
								(size 1.27 1.27)
							)
						)
					)
					(number "H10"
						(effects
							(font
								(size 1.27 1.27)
							)
						)
					)
				)
				(pin input line
					(at 0 -38.1 0)
					(length 5.08)
					(name "CA4_A"
						(effects
							(font
								(size 1.27 1.27)
							)
						)
					)
					(number "H11"
						(effects
							(font
								(size 1.27 1.27)
							)
						)
					)
				)
				(pin input line
					(at 0 -40.64 0)
					(length 5.08)
					(name "CA5_A"
						(effects
							(font
								(size 1.27 1.27)
							)
						)
					)
					(number "J11"
						(effects
							(font
								(size 1.27 1.27)
							)
						)
					)
				)
				(pin input line
					(at 0 -43.18 0)
					(length 5.08)
					(name "CKE0_A"
						(effects
							(font
								(size 1.27 1.27)
							)
						)
					)
					(number "J4"
						(effects
							(font
								(size 1.27 1.27)
							)
						)
					)
				)
				(pin input line
					(at 0 -50.8 0)
					(length 5.08)
					(name "ODT_CA_A"
						(effects
							(font
								(size 1.27 1.27)
							)
						)
					)
					(number "G2"
						(effects
							(font
								(size 1.27 1.27)
							)
						)
					)
				)
				(pin input line
					(at 0 -54.61 0)
					(length 5.08)
					(name "ZQ0"
						(effects
							(font
								(size 1.27 1.27)
							)
						)
					)
					(number "A5"
						(effects
							(font
								(size 1.27 1.27)
							)
						)
					)
				)
				(pin power_in line
					(at 0 -58.42 0)
					(length 5.08)
					(name "VSS"
						(effects
							(font
								(size 1.27 1.27)
							)
						)
					)
					(number "A10"
						(effects
							(font
								(size 1.27 1.27)
							)
						)
					)
				)
				(pin passive line
					(at 0 -58.42 0)
					(length 5.08)
					(hide yes)
					(name "VSS"
						(effects
							(font
								(size 1.27 1.27)
							)
						)
					)
					(number "A3"
						(effects
							(font
								(size 1.27 1.27)
							)
						)
					)
				)
				(pin passive line
					(at 0 -58.42 0)
					(length 5.08)
					(hide yes)
					(name "VSS"
						(effects
							(font
								(size 1.27 1.27)
							)
						)
					)
					(number "C1"
						(effects
							(font
								(size 1.27 1.27)
							)
						)
					)
				)
				(pin passive line
					(at 0 -58.42 0)
					(length 5.08)
					(hide yes)
					(name "VSS"
						(effects
							(font
								(size 1.27 1.27)
							)
						)
					)
					(number "C12"
						(effects
							(font
								(size 1.27 1.27)
							)
						)
					)
				)
				(pin passive line
					(at 0 -58.42 0)
					(length 5.08)
					(hide yes)
					(name "VSS"
						(effects
							(font
								(size 1.27 1.27)
							)
						)
					)
					(number "C5"
						(effects
							(font
								(size 1.27 1.27)
							)
						)
					)
				)
				(pin passive line
					(at 0 -58.42 0)
					(length 5.08)
					(hide yes)
					(name "VSS"
						(effects
							(font
								(size 1.27 1.27)
							)
						)
					)
					(number "C8"
						(effects
							(font
								(size 1.27 1.27)
							)
						)
					)
				)
				(pin passive line
					(at 0 -58.42 0)
					(length 5.08)
					(hide yes)
					(name "VSS"
						(effects
							(font
								(size 1.27 1.27)
							)
						)
					)
					(number "D11"
						(effects
							(font
								(size 1.27 1.27)
							)
						)
					)
				)
				(pin passive line
					(at 0 -58.42 0)
					(length 5.08)
					(hide yes)
					(name "VSS"
						(effects
							(font
								(size 1.27 1.27)
							)
						)
					)
					(number "D2"
						(effects
							(font
								(size 1.27 1.27)
							)
						)
					)
				)
				(pin passive line
					(at 0 -58.42 0)
					(length 5.08)
					(hide yes)
					(name "VSS"
						(effects
							(font
								(size 1.27 1.27)
							)
						)
					)
					(number "D4"
						(effects
							(font
								(size 1.27 1.27)
							)
						)
					)
				)
				(pin passive line
					(at 0 -58.42 0)
					(length 5.08)
					(hide yes)
					(name "VSS"
						(effects
							(font
								(size 1.27 1.27)
							)
						)
					)
					(number "D9"
						(effects
							(font
								(size 1.27 1.27)
							)
						)
					)
				)
				(pin passive line
					(at 0 -58.42 0)
					(length 5.08)
					(hide yes)
					(name "VSS"
						(effects
							(font
								(size 1.27 1.27)
							)
						)
					)
					(number "E1"
						(effects
							(font
								(size 1.27 1.27)
							)
						)
					)
				)
				(pin passive line
					(at 0 -58.42 0)
					(length 5.08)
					(hide yes)
					(name "VSS"
						(effects
							(font
								(size 1.27 1.27)
							)
						)
					)
					(number "E12"
						(effects
							(font
								(size 1.27 1.27)
							)
						)
					)
				)
				(pin passive line
					(at 0 -58.42 0)
					(length 5.08)
					(hide yes)
					(name "VSS"
						(effects
							(font
								(size 1.27 1.27)
							)
						)
					)
					(number "E5"
						(effects
							(font
								(size 1.27 1.27)
							)
						)
					)
				)
				(pin passive line
					(at 0 -58.42 0)
					(length 5.08)
					(hide yes)
					(name "VSS"
						(effects
							(font
								(size 1.27 1.27)
							)
						)
					)
					(number "E8"
						(effects
							(font
								(size 1.27 1.27)
							)
						)
					)
				)
				(pin passive line
					(at 0 -58.42 0)
					(length 5.08)
					(hide yes)
					(name "VSS"
						(effects
							(font
								(size 1.27 1.27)
							)
						)
					)
					(number "G1"
						(effects
							(font
								(size 1.27 1.27)
							)
						)
					)
				)
				(pin passive line
					(at 0 -58.42 0)
					(length 5.08)
					(hide yes)
					(name "VSS"
						(effects
							(font
								(size 1.27 1.27)
							)
						)
					)
					(number "G10"
						(effects
							(font
								(size 1.27 1.27)
							)
						)
					)
				)
				(pin passive line
					(at 0 -58.42 0)
					(length 5.08)
					(hide yes)
					(name "VSS"
						(effects
							(font
								(size 1.27 1.27)
							)
						)
					)
					(number "G12"
						(effects
							(font
								(size 1.27 1.27)
							)
						)
					)
				)
				(pin passive line
					(at 0 -58.42 0)
					(length 5.08)
					(hide yes)
					(name "VSS"
						(effects
							(font
								(size 1.27 1.27)
							)
						)
					)
					(number "G3"
						(effects
							(font
								(size 1.27 1.27)
							)
						)
					)
				)
				(pin passive line
					(at 0 -58.42 0)
					(length 5.08)
					(hide yes)
					(name "VSS"
						(effects
							(font
								(size 1.27 1.27)
							)
						)
					)
					(number "G5"
						(effects
							(font
								(size 1.27 1.27)
							)
						)
					)
				)
				(pin passive line
					(at 0 -58.42 0)
					(length 5.08)
					(hide yes)
					(name "VSS"
						(effects
							(font
								(size 1.27 1.27)
							)
						)
					)
					(number "G8"
						(effects
							(font
								(size 1.27 1.27)
							)
						)
					)
				)
				(pin passive line
					(at 0 -58.42 0)
					(length 5.08)
					(hide yes)
					(name "VSS"
						(effects
							(font
								(size 1.27 1.27)
							)
						)
					)
					(number "J1"
						(effects
							(font
								(size 1.27 1.27)
							)
						)
					)
				)
				(pin passive line
					(at 0 -58.42 0)
					(length 5.08)
					(hide yes)
					(name "VSS"
						(effects
							(font
								(size 1.27 1.27)
							)
						)
					)
					(number "J10"
						(effects
							(font
								(size 1.27 1.27)
							)
						)
					)
				)
				(pin passive line
					(at 0 -58.42 0)
					(length 5.08)
					(hide yes)
					(name "VSS"
						(effects
							(font
								(size 1.27 1.27)
							)
						)
					)
					(number "J12"
						(effects
							(font
								(size 1.27 1.27)
							)
						)
					)
				)
				(pin passive line
					(at 0 -58.42 0)
					(length 5.08)
					(hide yes)
					(name "VSS"
						(effects
							(font
								(size 1.27 1.27)
							)
						)
					)
					(number "J3"
						(effects
							(font
								(size 1.27 1.27)
							)
						)
					)
				)
				(pin passive line
					(at 0 -58.42 0)
					(length 5.08)
					(hide yes)
					(name "VSS"
						(effects
							(font
								(size 1.27 1.27)
							)
						)
					)
					(number "K11"
						(effects
							(font
								(size 1.27 1.27)
							)
						)
					)
				)
				(pin passive line
					(at 0 -58.42 0)
					(length 5.08)
					(hide yes)
					(name "VSS"
						(effects
							(font
								(size 1.27 1.27)
							)
						)
					)
					(number "K2"
						(effects
							(font
								(size 1.27 1.27)
							)
						)
					)
				)
				(pin passive line
					(at 0 -58.42 0)
					(length 5.08)
					(hide yes)
					(name "VSS"
						(effects
							(font
								(size 1.27 1.27)
							)
						)
					)
					(number "K4"
						(effects
							(font
								(size 1.27 1.27)
							)
						)
					)
				)
				(pin passive line
					(at 0 -58.42 0)
					(length 5.08)
					(hide yes)
					(name "VSS"
						(effects
							(font
								(size 1.27 1.27)
							)
						)
					)
					(number "K9"
						(effects
							(font
								(size 1.27 1.27)
							)
						)
					)
				)
				(pin no_connect line
					(at 5.08 -22.86 0)
					(length 5.08)
					(hide yes)
					(name "DNU"
						(effects
							(font
								(size 1.27 1.27)
							)
						)
					)
					(number "A2"
						(effects
							(font
								(size 1.27 1.27)
							)
						)
					)
				)
				(pin no_connect line
					(at 5.08 -25.4 0)
					(length 5.08)
					(hide yes)
					(name "DNU"
						(effects
							(font
								(size 1.27 1.27)
							)
						)
					)
					(number "B12"
						(effects
							(font
								(size 1.27 1.27)
							)
						)
					)
				)
				(pin no_connect line
					(at 5.08 -45.72 0)
					(length 5.08)
					(hide yes)
					(name "DNU"
						(effects
							(font
								(size 1.27 1.27)
							)
						)
					)
					(number "B1"
						(effects
							(font
								(size 1.27 1.27)
							)
						)
					)
				)
				(pin no_connect line
					(at 5.08 -48.26 0)
					(length 5.08)
					(hide yes)
					(name "NC"
						(effects
							(font
								(size 1.27 1.27)
							)
						)
					)
					(number "H3"
						(effects
							(font
								(size 1.27 1.27)
							)
						)
					)
				)
				(pin no_connect line
					(at 12.7 -60.96 90)
					(length 5.08)
					(hide yes)
					(name "NC"
						(effects
							(font
								(size 1.27 1.27)
							)
						)
					)
					(number "K5"
						(effects
							(font
								(size 1.27 1.27)
							)
						)
					)
				)
				(pin no_connect line
					(at 15.24 -60.96 90)
					(length 5.08)
					(hide yes)
					(name "NC"
						(effects
							(font
								(size 1.27 1.27)
							)
						)
					)
					(number "J5"
						(effects
							(font
								(size 1.27 1.27)
							)
						)
					)
				)
				(pin no_connect line
					(at 17.78 -60.96 90)
					(length 5.08)
					(hide yes)
					(name "DNU"
						(effects
							(font
								(size 1.27 1.27)
							)
						)
					)
					(number "A1"
						(effects
							(font
								(size 1.27 1.27)
							)
						)
					)
				)
				(pin no_connect line
					(at 20.32 -60.96 90)
					(length 5.08)
					(hide yes)
					(name "DNU"
						(effects
							(font
								(size 1.27 1.27)
							)
						)
					)
					(number "A11"
						(effects
							(font
								(size 1.27 1.27)
							)
						)
					)
				)
				(pin no_connect line
					(at 22.86 -60.96 90)
					(length 5.08)
					(hide yes)
					(name "DNU"
						(effects
							(font
								(size 1.27 1.27)
							)
						)
					)
					(number "A12"
						(effects
							(font
								(size 1.27 1.27)
							)
						)
					)
				)
				(pin no_connect line
					(at 35.56 -29.21 180)
					(length 5.08)
					(hide yes)
					(name "NC"
						(effects
							(font
								(size 1.27 1.27)
							)
						)
					)
					(number "K8"
						(effects
							(font
								(size 1.27 1.27)
							)
						)
					)
				)
				(pin bidirectional line
					(at 40.64 0 180)
					(length 5.08)
					(name "DQS0_T_A"
						(effects
							(font
								(size 1.27 1.27)
							)
						)
					)
					(number "D3"
						(effects
							(font
								(size 1.27 1.27)
							)
						)
					)
				)
				(pin bidirectional line
					(at 40.64 -2.54 180)
					(length 5.08)
					(name "DQS0_C_A"
						(effects
							(font
								(size 1.27 1.27)
							)
						)
					)
					(number "E3"
						(effects
							(font
								(size 1.27 1.27)
							)
						)
					)
				)
				(pin bidirectional line
					(at 40.64 -5.08 180)
					(length 5.08)
					(name "DQ0_A"
						(effects
							(font
								(size 1.27 1.27)
							)
						)
					)
					(number "B2"
						(effects
							(font
								(size 1.27 1.27)
							)
						)
					)
				)
				(pin bidirectional line
					(at 40.64 -7.62 180)
					(length 5.08)
					(name "DQ1_A"
						(effects
							(font
								(size 1.27 1.27)
							)
						)
					)
					(number "C2"
						(effects
							(font
								(size 1.27 1.27)
							)
						)
					)
				)
				(pin bidirectional line
					(at 40.64 -10.16 180)
					(length 5.08)
					(name "DQ2_A"
						(effects
							(font
								(size 1.27 1.27)
							)
						)
					)
					(number "E2"
						(effects
							(font
								(size 1.27 1.27)
							)
						)
					)
				)
				(pin bidirectional line
					(at 40.64 -12.7 180)
					(length 5.08)
					(name "DQ3_A"
						(effects
							(font
								(size 1.27 1.27)
							)
						)
					)
					(number "F2"
						(effects
							(font
								(size 1.27 1.27)
							)
						)
					)
				)
				(pin bidirectional line
					(at 40.64 -15.24 180)
					(length 5.08)
					(name "DQ4_A"
						(effects
							(font
								(size 1.27 1.27)
							)
						)
					)
					(number "F4"
						(effects
							(font
								(size 1.27 1.27)
							)
						)
					)
				)
				(pin bidirectional line
					(at 40.64 -17.78 180)
					(length 5.08)
					(name "DQ5_A"
						(effects
							(font
								(size 1.27 1.27)
							)
						)
					)
					(number "E4"
						(effects
							(font
								(size 1.27 1.27)
							)
						)
					)
				)
				(pin bidirectional line
					(at 40.64 -20.32 180)
					(length 5.08)
					(name "DQ6_A"
						(effects
							(font
								(size 1.27 1.27)
							)
						)
					)
					(number "C4"
						(effects
							(font
								(size 1.27 1.27)
							)
						)
					)
				)
				(pin bidirectional line
					(at 40.64 -22.86 180)
					(length 5.08)
					(name "DQ7_A"
						(effects
							(font
								(size 1.27 1.27)
							)
						)
					)
					(number "B4"
						(effects
							(font
								(size 1.27 1.27)
							)
						)
					)
				)
				(pin bidirectional line
					(at 40.64 -25.4 180)
					(length 5.08)
					(name "DMI0_A"
						(effects
							(font
								(size 1.27 1.27)
							)
						)
					)
					(number "C3"
						(effects
							(font
								(size 1.27 1.27)
							)
						)
					)
				)
				(pin bidirectional line
					(at 40.64 -33.02 180)
					(length 5.08)
					(name "DQS1_T_A"
						(effects
							(font
								(size 1.27 1.27)
							)
						)
					)
					(number "D10"
						(effects
							(font
								(size 1.27 1.27)
							)
						)
					)
				)
				(pin bidirectional line
					(at 40.64 -35.56 180)
					(length 5.08)
					(name "DQS1_C_A"
						(effects
							(font
								(size 1.27 1.27)
							)
						)
					)
					(number "E10"
						(effects
							(font
								(size 1.27 1.27)
							)
						)
					)
				)
				(pin bidirectional line
					(at 40.64 -38.1 180)
					(length 5.08)
					(name "DQ8_A"
						(effects
							(font
								(size 1.27 1.27)
							)
						)
					)
					(number "B11"
						(effects
							(font
								(size 1.27 1.27)
							)
						)
					)
				)
				(pin bidirectional line
					(at 40.64 -40.64 180)
					(length 5.08)
					(name "DQ9_A"
						(effects
							(font
								(size 1.27 1.27)
							)
						)
					)
					(number "C11"
						(effects
							(font
								(size 1.27 1.27)
							)
						)
					)
				)
				(pin bidirectional line
					(at 40.64 -43.18 180)
					(length 5.08)
					(name "DQ10_A"
						(effects
							(font
								(size 1.27 1.27)
							)
						)
					)
					(number "E11"
						(effects
							(font
								(size 1.27 1.27)
							)
						)
					)
				)
				(pin bidirectional line
					(at 40.64 -45.72 180)
					(length 5.08)
					(name "DQ11_A"
						(effects
							(font
								(size 1.27 1.27)
							)
						)
					)
					(number "F11"
						(effects
							(font
								(size 1.27 1.27)
							)
						)
					)
				)
				(pin bidirectional line
					(at 40.64 -48.26 180)
					(length 5.08)
					(name "DQ12_A"
						(effects
							(font
								(size 1.27 1.27)
							)
						)
					)
					(number "F9"
						(effects
							(font
								(size 1.27 1.27)
							)
						)
					)
				)
				(pin bidirectional line
					(at 40.64 -50.8 180)
					(length 5.08)
					(name "DQ13_A"
						(effects
							(font
								(size 1.27 1.27)
							)
						)
					)
					(number "E9"
						(effects
							(font
								(size 1.27 1.27)
							)
						)
					)
				)
				(pin bidirectional line
					(at 40.64 -53.34 180)
					(length 5.08)
					(name "DQ14_A"
						(effects
							(font
								(size 1.27 1.27)
							)
						)
					)
					(number "C9"
						(effects
							(font
								(size 1.27 1.27)
							)
						)
					)
				)
				(pin bidirectional line
					(at 40.64 -55.88 180)
					(length 5.08)
					(name "DQ15_A"
						(effects
							(font
								(size 1.27 1.27)
							)
						)
					)
					(number "B9"
						(effects
							(font
								(size 1.27 1.27)
							)
						)
					)
				)
				(pin bidirectional line
					(at 40.64 -58.42 180)
					(length 5.08)
					(name "DMI1_A"
						(effects
							(font
								(size 1.27 1.27)
							)
						)
					)
					(number "C10"
						(effects
							(font
								(size 1.27 1.27)
							)
						)
					)
				)
			)
			(symbol "MT53E1G32D2NP-046_2_1"
				(rectangle
					(start 5.08 2.54)
					(end 35.56 -60.96)
					(stroke
						(width 0.254)
						(type default)
					)
					(fill
						(type background)
					)
				)
				(pin power_in line
					(at 0 0 0)
					(length 5.08)
					(name "VDDQ"
						(effects
							(font
								(size 1.27 1.27)
							)
						)
					)
					(number "AA10"
						(effects
							(font
								(size 1.27 1.27)
							)
						)
					)
				)
				(pin passive line
					(at 0 0 0)
					(length 5.08)
					(hide yes)
					(name "VDDQ"
						(effects
							(font
								(size 1.27 1.27)
							)
						)
					)
					(number "AA3"
						(effects
							(font
								(size 1.27 1.27)
							)
						)
					)
				)
				(pin passive line
					(at 0 0 0)
					(length 5.08)
					(hide yes)
					(name "VDDQ"
						(effects
							(font
								(size 1.27 1.27)
							)
						)
					)
					(number "AA5"
						(effects
							(font
								(size 1.27 1.27)
							)
						)
					)
				)
				(pin passive line
					(at 0 0 0)
					(length 5.08)
					(hide yes)
					(name "VDDQ"
						(effects
							(font
								(size 1.27 1.27)
							)
						)
					)
					(number "AA8"
						(effects
							(font
								(size 1.27 1.27)
							)
						)
					)
				)
				(pin passive line
					(at 0 0 0)
					(length 5.08)
					(hide yes)
					(name "VDDQ"
						(effects
							(font
								(size 1.27 1.27)
							)
						)
					)
					(number "U10"
						(effects
							(font
								(size 1.27 1.27)
							)
						)
					)
				)
				(pin passive line
					(at 0 0 0)
					(length 5.08)
					(hide yes)
					(name "VDDQ"
						(effects
							(font
								(size 1.27 1.27)
							)
						)
					)
					(number "U3"
						(effects
							(font
								(size 1.27 1.27)
							)
						)
					)
				)
				(pin passive line
					(at 0 0 0)
					(length 5.08)
					(hide yes)
					(name "VDDQ"
						(effects
							(font
								(size 1.27 1.27)
							)
						)
					)
					(number "W1"
						(effects
							(font
								(size 1.27 1.27)
							)
						)
					)
				)
				(pin passive line
					(at 0 0 0)
					(length 5.08)
					(hide yes)
					(name "VDDQ"
						(effects
							(font
								(size 1.27 1.27)
							)
						)
					)
					(number "W12"
						(effects
							(font
								(size 1.27 1.27)
							)
						)
					)
				)
				(pin passive line
					(at 0 0 0)
					(length 5.08)
					(hide yes)
					(name "VDDQ"
						(effects
							(font
								(size 1.27 1.27)
							)
						)
					)
					(number "W5"
						(effects
							(font
								(size 1.27 1.27)
							)
						)
					)
				)
				(pin passive line
					(at 0 0 0)
					(length 5.08)
					(hide yes)
					(name "VDDQ"
						(effects
							(font
								(size 1.27 1.27)
							)
						)
					)
					(number "W8"
						(effects
							(font
								(size 1.27 1.27)
							)
						)
					)
				)
				(pin power_in line
					(at 0 -7.62 0)
					(length 5.08)
					(name "VDD1"
						(effects
							(font
								(size 1.27 1.27)
							)
						)
					)
					(number "T4"
						(effects
							(font
								(size 1.27 1.27)
							)
						)
					)
				)
				(pin passive line
					(at 0 -7.62 0)
					(length 5.08)
					(hide yes)
					(name "VDD1"
						(effects
							(font
								(size 1.27 1.27)
							)
						)
					)
					(number "T9"
						(effects
							(font
								(size 1.27 1.27)
							)
						)
					)
				)
				(pin passive line
					(at 0 -7.62 0)
					(length 5.08)
					(hide yes)
					(name "VDD1"
						(effects
							(font
								(size 1.27 1.27)
							)
						)
					)
					(number "U1"
						(effects
							(font
								(size 1.27 1.27)
							)
						)
					)
				)
				(pin passive line
					(at 0 -7.62 0)
					(length 5.08)
					(hide yes)
					(name "VDD1"
						(effects
							(font
								(size 1.27 1.27)
							)
						)
					)
					(number "U12"
						(effects
							(font
								(size 1.27 1.27)
							)
						)
					)
				)
				(pin power_in line
					(at 0 -10.16 0)
					(length 5.08)
					(name "VDD2"
						(effects
							(font
								(size 1.27 1.27)
							)
						)
					)
					(number "AB4"
						(effects
							(font
								(size 1.27 1.27)
							)
						)
					)
				)
				(pin passive line
					(at 0 -10.16 0)
					(length 5.08)
					(hide yes)
					(name "VDD2"
						(effects
							(font
								(size 1.27 1.27)
							)
						)
					)
					(number "AB9"
						(effects
							(font
								(size 1.27 1.27)
							)
						)
					)
				)
				(pin passive line
					(at 0 -10.16 0)
					(length 5.08)
					(hide yes)
					(name "VDD2"
						(effects
							(font
								(size 1.27 1.27)
							)
						)
					)
					(number "N1"
						(effects
							(font
								(size 1.27 1.27)
							)
						)
					)
				)
				(pin passive line
					(at 0 -10.16 0)
					(length 5.08)
					(hide yes)
					(name "VDD2"
						(effects
							(font
								(size 1.27 1.27)
							)
						)
					)
					(number "N10"
						(effects
							(font
								(size 1.27 1.27)
							)
						)
					)
				)
				(pin passive line
					(at 0 -10.16 0)
					(length 5.08)
					(hide yes)
					(name "VDD2"
						(effects
							(font
								(size 1.27 1.27)
							)
						)
					)
					(number "N12"
						(effects
							(font
								(size 1.27 1.27)
							)
						)
					)
				)
				(pin passive line
					(at 0 -10.16 0)
					(length 5.08)
					(hide yes)
					(name "VDD2"
						(effects
							(font
								(size 1.27 1.27)
							)
						)
					)
					(number "N3"
						(effects
							(font
								(size 1.27 1.27)
							)
						)
					)
				)
				(pin passive line
					(at 0 -10.16 0)
					(length 5.08)
					(hide yes)
					(name "VDD2"
						(effects
							(font
								(size 1.27 1.27)
							)
						)
					)
					(number "R1"
						(effects
							(font
								(size 1.27 1.27)
							)
						)
					)
				)
				(pin passive line
					(at 0 -10.16 0)
					(length 5.08)
					(hide yes)
					(name "VDD2"
						(effects
							(font
								(size 1.27 1.27)
							)
						)
					)
					(number "R12"
						(effects
							(font
								(size 1.27 1.27)
							)
						)
					)
				)
				(pin passive line
					(at 0 -10.16 0)
					(length 5.08)
					(hide yes)
					(name "VDD2"
						(effects
							(font
								(size 1.27 1.27)
							)
						)
					)
					(number "R5"
						(effects
							(font
								(size 1.27 1.27)
							)
						)
					)
				)
				(pin passive line
					(at 0 -10.16 0)
					(length 5.08)
					(hide yes)
					(name "VDD2"
						(effects
							(font
								(size 1.27 1.27)
							)
						)
					)
					(number "R8"
						(effects
							(font
								(size 1.27 1.27)
							)
						)
					)
				)
				(pin passive line
					(at 0 -10.16 0)
					(length 5.08)
					(hide yes)
					(name "VDD2"
						(effects
							(font
								(size 1.27 1.27)
							)
						)
					)
					(number "U5"
						(effects
							(font
								(size 1.27 1.27)
							)
						)
					)
				)
				(pin passive line
					(at 0 -10.16 0)
					(length 5.08)
					(hide yes)
					(name "VDD2"
						(effects
							(font
								(size 1.27 1.27)
							)
						)
					)
					(number "U8"
						(effects
							(font
								(size 1.27 1.27)
							)
						)
					)
				)
				(pin input line
					(at 0 -15.24 0)
					(length 5.08)
					(name "CK_T_B"
						(effects
							(font
								(size 1.27 1.27)
							)
						)
					)
					(number "P8"
						(effects
							(font
								(size 1.27 1.27)
							)
						)
					)
				)
				(pin input line
					(at 0 -17.78 0)
					(length 5.08)
					(name "CK_C_B"
						(effects
							(font
								(size 1.27 1.27)
							)
						)
					)
					(number "P9"
						(effects
							(font
								(size 1.27 1.27)
							)
						)
					)
				)
				(pin input line
					(at 0 -20.32 0)
					(length 5.08)
					(name "CS0_B"
						(effects
							(font
								(size 1.27 1.27)
							)
						)
					)
					(number "R4"
						(effects
							(font
								(size 1.27 1.27)
							)
						)
					)
				)
				(pin input line
					(at 0 -27.94 0)
					(length 5.08)
					(name "CA0_B"
						(effects
							(font
								(size 1.27 1.27)
							)
						)
					)
					(number "R2"
						(effects
							(font
								(size 1.27 1.27)
							)
						)
					)
				)
				(pin input line
					(at 0 -30.48 0)
					(length 5.08)
					(name "CA1_B"
						(effects
							(font
								(size 1.27 1.27)
							)
						)
					)
					(number "P2"
						(effects
							(font
								(size 1.27 1.27)
							)
						)
					)
				)
				(pin input line
					(at 0 -33.02 0)
					(length 5.08)
					(name "CA2_B"
						(effects
							(font
								(size 1.27 1.27)
							)
						)
					)
					(number "R9"
						(effects
							(font
								(size 1.27 1.27)
							)
						)
					)
				)
				(pin input line
					(at 0 -35.56 0)
					(length 5.08)
					(name "CA3_B"
						(effects
							(font
								(size 1.27 1.27)
							)
						)
					)
					(number "R10"
						(effects
							(font
								(size 1.27 1.27)
							)
						)
					)
				)
				(pin input line
					(at 0 -38.1 0)
					(length 5.08)
					(name "CA4_B"
						(effects
							(font
								(size 1.27 1.27)
							)
						)
					)
					(number "R11"
						(effects
							(font
								(size 1.27 1.27)
							)
						)
					)
				)
				(pin input line
					(at 0 -40.64 0)
					(length 5.08)
					(name "CA5_B"
						(effects
							(font
								(size 1.27 1.27)
							)
						)
					)
					(number "P11"
						(effects
							(font
								(size 1.27 1.27)
							)
						)
					)
				)
				(pin input line
					(at 0 -43.18 0)
					(length 5.08)
					(name "CKE0_B"
						(effects
							(font
								(size 1.27 1.27)
							)
						)
					)
					(number "P4"
						(effects
							(font
								(size 1.27 1.27)
							)
						)
					)
				)
				(pin input line
					(at 0 -50.8 0)
					(length 5.08)
					(name "ODT_CA_B"
						(effects
							(font
								(size 1.27 1.27)
							)
						)
					)
					(number "T2"
						(effects
							(font
								(size 1.27 1.27)
							)
						)
					)
				)
				(pin power_in line
					(at 0 -58.42 0)
					(length 5.08)
					(name "VSS"
						(effects
							(font
								(size 1.27 1.27)
							)
						)
					)
					(number "AB10"
						(effects
							(font
								(size 1.27 1.27)
							)
						)
					)
				)
				(pin passive line
					(at 0 -58.42 0)
					(length 5.08)
					(hide yes)
					(name "VSS"
						(effects
							(font
								(size 1.27 1.27)
							)
						)
					)
					(number "AB3"
						(effects
							(font
								(size 1.27 1.27)
							)
						)
					)
				)
				(pin passive line
					(at 0 -58.42 0)
					(length 5.08)
					(hide yes)
					(name "VSS"
						(effects
							(font
								(size 1.27 1.27)
							)
						)
					)
					(number "AB5"
						(effects
							(font
								(size 1.27 1.27)
							)
						)
					)
				)
				(pin passive line
					(at 0 -58.42 0)
					(length 5.08)
					(hide yes)
					(name "VSS"
						(effects
							(font
								(size 1.27 1.27)
							)
						)
					)
					(number "AB8"
						(effects
							(font
								(size 1.27 1.27)
							)
						)
					)
				)
				(pin passive line
					(at 0 -58.42 0)
					(length 5.08)
					(hide yes)
					(name "VSS"
						(effects
							(font
								(size 1.27 1.27)
							)
						)
					)
					(number "N11"
						(effects
							(font
								(size 1.27 1.27)
							)
						)
					)
				)
				(pin passive line
					(at 0 -58.42 0)
					(length 5.08)
					(hide yes)
					(name "VSS"
						(effects
							(font
								(size 1.27 1.27)
							)
						)
					)
					(number "N2"
						(effects
							(font
								(size 1.27 1.27)
							)
						)
					)
				)
				(pin passive line
					(at 0 -58.42 0)
					(length 5.08)
					(hide yes)
					(name "VSS"
						(effects
							(font
								(size 1.27 1.27)
							)
						)
					)
					(number "N4"
						(effects
							(font
								(size 1.27 1.27)
							)
						)
					)
				)
				(pin passive line
					(at 0 -58.42 0)
					(length 5.08)
					(hide yes)
					(name "VSS"
						(effects
							(font
								(size 1.27 1.27)
							)
						)
					)
					(number "N9"
						(effects
							(font
								(size 1.27 1.27)
							)
						)
					)
				)
				(pin passive line
					(at 0 -58.42 0)
					(length 5.08)
					(hide yes)
					(name "VSS"
						(effects
							(font
								(size 1.27 1.27)
							)
						)
					)
					(number "P1"
						(effects
							(font
								(size 1.27 1.27)
							)
						)
					)
				)
				(pin passive line
					(at 0 -58.42 0)
					(length 5.08)
					(hide yes)
					(name "VSS"
						(effects
							(font
								(size 1.27 1.27)
							)
						)
					)
					(number "P10"
						(effects
							(font
								(size 1.27 1.27)
							)
						)
					)
				)
				(pin passive line
					(at 0 -58.42 0)
					(length 5.08)
					(hide yes)
					(name "VSS"
						(effects
							(font
								(size 1.27 1.27)
							)
						)
					)
					(number "P12"
						(effects
							(font
								(size 1.27 1.27)
							)
						)
					)
				)
				(pin passive line
					(at 0 -58.42 0)
					(length 5.08)
					(hide yes)
					(name "VSS"
						(effects
							(font
								(size 1.27 1.27)
							)
						)
					)
					(number "P3"
						(effects
							(font
								(size 1.27 1.27)
							)
						)
					)
				)
				(pin passive line
					(at 0 -58.42 0)
					(length 5.08)
					(hide yes)
					(name "VSS"
						(effects
							(font
								(size 1.27 1.27)
							)
						)
					)
					(number "T1"
						(effects
							(font
								(size 1.27 1.27)
							)
						)
					)
				)
				(pin passive line
					(at 0 -58.42 0)
					(length 5.08)
					(hide yes)
					(name "VSS"
						(effects
							(font
								(size 1.27 1.27)
							)
						)
					)
					(number "T10"
						(effects
							(font
								(size 1.27 1.27)
							)
						)
					)
				)
				(pin passive line
					(at 0 -58.42 0)
					(length 5.08)
					(hide yes)
					(name "VSS"
						(effects
							(font
								(size 1.27 1.27)
							)
						)
					)
					(number "T12"
						(effects
							(font
								(size 1.27 1.27)
							)
						)
					)
				)
				(pin passive line
					(at 0 -58.42 0)
					(length 5.08)
					(hide yes)
					(name "VSS"
						(effects
							(font
								(size 1.27 1.27)
							)
						)
					)
					(number "T3"
						(effects
							(font
								(size 1.27 1.27)
							)
						)
					)
				)
				(pin passive line
					(at 0 -58.42 0)
					(length 5.08)
					(hide yes)
					(name "VSS"
						(effects
							(font
								(size 1.27 1.27)
							)
						)
					)
					(number "T5"
						(effects
							(font
								(size 1.27 1.27)
							)
						)
					)
				)
				(pin passive line
					(at 0 -58.42 0)
					(length 5.08)
					(hide yes)
					(name "VSS"
						(effects
							(font
								(size 1.27 1.27)
							)
						)
					)
					(number "T8"
						(effects
							(font
								(size 1.27 1.27)
							)
						)
					)
				)
				(pin passive line
					(at 0 -58.42 0)
					(length 5.08)
					(hide yes)
					(name "VSS"
						(effects
							(font
								(size 1.27 1.27)
							)
						)
					)
					(number "V1"
						(effects
							(font
								(size 1.27 1.27)
							)
						)
					)
				)
				(pin passive line
					(at 0 -58.42 0)
					(length 5.08)
					(hide yes)
					(name "VSS"
						(effects
							(font
								(size 1.27 1.27)
							)
						)
					)
					(number "V12"
						(effects
							(font
								(size 1.27 1.27)
							)
						)
					)
				)
				(pin passive line
					(at 0 -58.42 0)
					(length 5.08)
					(hide yes)
					(name "VSS"
						(effects
							(font
								(size 1.27 1.27)
							)
						)
					)
					(number "V5"
						(effects
							(font
								(size 1.27 1.27)
							)
						)
					)
				)
				(pin passive line
					(at 0 -58.42 0)
					(length 5.08)
					(hide yes)
					(name "VSS"
						(effects
							(font
								(size 1.27 1.27)
							)
						)
					)
					(number "V8"
						(effects
							(font
								(size 1.27 1.27)
							)
						)
					)
				)
				(pin passive line
					(at 0 -58.42 0)
					(length 5.08)
					(hide yes)
					(name "VSS"
						(effects
							(font
								(size 1.27 1.27)
							)
						)
					)
					(number "W11"
						(effects
							(font
								(size 1.27 1.27)
							)
						)
					)
				)
				(pin passive line
					(at 0 -58.42 0)
					(length 5.08)
					(hide yes)
					(name "VSS"
						(effects
							(font
								(size 1.27 1.27)
							)
						)
					)
					(number "W2"
						(effects
							(font
								(size 1.27 1.27)
							)
						)
					)
				)
				(pin passive line
					(at 0 -58.42 0)
					(length 5.08)
					(hide yes)
					(name "VSS"
						(effects
							(font
								(size 1.27 1.27)
							)
						)
					)
					(number "W4"
						(effects
							(font
								(size 1.27 1.27)
							)
						)
					)
				)
				(pin passive line
					(at 0 -58.42 0)
					(length 5.08)
					(hide yes)
					(name "VSS"
						(effects
							(font
								(size 1.27 1.27)
							)
						)
					)
					(number "W9"
						(effects
							(font
								(size 1.27 1.27)
							)
						)
					)
				)
				(pin passive line
					(at 0 -58.42 0)
					(length 5.08)
					(hide yes)
					(name "VSS"
						(effects
							(font
								(size 1.27 1.27)
							)
						)
					)
					(number "Y1"
						(effects
							(font
								(size 1.27 1.27)
							)
						)
					)
				)
				(pin passive line
					(at 0 -58.42 0)
					(length 5.08)
					(hide yes)
					(name "VSS"
						(effects
							(font
								(size 1.27 1.27)
							)
						)
					)
					(number "Y12"
						(effects
							(font
								(size 1.27 1.27)
							)
						)
					)
				)
				(pin passive line
					(at 0 -58.42 0)
					(length 5.08)
					(hide yes)
					(name "VSS"
						(effects
							(font
								(size 1.27 1.27)
							)
						)
					)
					(number "Y5"
						(effects
							(font
								(size 1.27 1.27)
							)
						)
					)
				)
				(pin passive line
					(at 0 -58.42 0)
					(length 5.08)
					(hide yes)
					(name "VSS"
						(effects
							(font
								(size 1.27 1.27)
							)
						)
					)
					(number "Y8"
						(effects
							(font
								(size 1.27 1.27)
							)
						)
					)
				)
				(pin no_connect line
					(at 5.08 -22.86 0)
					(length 5.08)
					(hide yes)
					(name "NC"
						(effects
							(font
								(size 1.27 1.27)
							)
						)
					)
					(number "A8"
						(effects
							(font
								(size 1.27 1.27)
							)
						)
					)
				)
				(pin no_connect line
					(at 5.08 -25.4 0)
					(length 5.08)
					(hide yes)
					(name "NC"
						(effects
							(font
								(size 1.27 1.27)
							)
						)
					)
					(number "G11"
						(effects
							(font
								(size 1.27 1.27)
							)
						)
					)
				)
				(pin no_connect line
					(at 5.08 -45.72 0)
					(length 5.08)
					(hide yes)
					(name "NC"
						(effects
							(font
								(size 1.27 1.27)
							)
						)
					)
					(number "P5"
						(effects
							(font
								(size 1.27 1.27)
							)
						)
					)
				)
				(pin no_connect line
					(at 5.08 -48.26 0)
					(length 5.08)
					(hide yes)
					(name "NC"
						(effects
							(font
								(size 1.27 1.27)
							)
						)
					)
					(number "N8"
						(effects
							(font
								(size 1.27 1.27)
							)
						)
					)
				)
				(pin no_connect line
					(at 5.08 -53.34 0)
					(length 5.08)
					(hide yes)
					(name "NC"
						(effects
							(font
								(size 1.27 1.27)
							)
						)
					)
					(number "R3"
						(effects
							(font
								(size 1.27 1.27)
							)
						)
					)
				)
				(pin no_connect line
					(at 5.08 -55.88 0)
					(length 5.08)
					(hide yes)
					(name "NC"
						(effects
							(font
								(size 1.27 1.27)
							)
						)
					)
					(number "N5"
						(effects
							(font
								(size 1.27 1.27)
							)
						)
					)
				)
				(pin no_connect line
					(at 35.56 -29.21 180)
					(length 5.08)
					(hide yes)
					(name "DNU"
						(effects
							(font
								(size 1.27 1.27)
							)
						)
					)
					(number "AA1"
						(effects
							(font
								(size 1.27 1.27)
							)
						)
					)
				)
				(pin no_connect line
					(at 35.56 -29.21 180)
					(length 5.08)
					(hide yes)
					(name "DNU"
						(effects
							(font
								(size 1.27 1.27)
							)
						)
					)
					(number "AA12"
						(effects
							(font
								(size 1.27 1.27)
							)
						)
					)
				)
				(pin no_connect line
					(at 35.56 -29.21 180)
					(length 5.08)
					(hide yes)
					(name "DNU"
						(effects
							(font
								(size 1.27 1.27)
							)
						)
					)
					(number "AB1"
						(effects
							(font
								(size 1.27 1.27)
							)
						)
					)
				)
				(pin no_connect line
					(at 35.56 -29.21 180)
					(length 5.08)
					(hide yes)
					(name "DNU"
						(effects
							(font
								(size 1.27 1.27)
							)
						)
					)
					(number "AB11"
						(effects
							(font
								(size 1.27 1.27)
							)
						)
					)
				)
				(pin no_connect line
					(at 35.56 -29.21 180)
					(length 5.08)
					(hide yes)
					(name "DNU"
						(effects
							(font
								(size 1.27 1.27)
							)
						)
					)
					(number "AB12"
						(effects
							(font
								(size 1.27 1.27)
							)
						)
					)
				)
				(pin no_connect line
					(at 35.56 -29.21 180)
					(length 5.08)
					(hide yes)
					(name "DNU"
						(effects
							(font
								(size 1.27 1.27)
							)
						)
					)
					(number "AB2"
						(effects
							(font
								(size 1.27 1.27)
							)
						)
					)
				)
				(pin bidirectional line
					(at 40.64 0 180)
					(length 5.08)
					(name "DQS0_T_B"
						(effects
							(font
								(size 1.27 1.27)
							)
						)
					)
					(number "W3"
						(effects
							(font
								(size 1.27 1.27)
							)
						)
					)
				)
				(pin bidirectional line
					(at 40.64 -2.54 180)
					(length 5.08)
					(name "DQS0_C_B"
						(effects
							(font
								(size 1.27 1.27)
							)
						)
					)
					(number "V3"
						(effects
							(font
								(size 1.27 1.27)
							)
						)
					)
				)
				(pin bidirectional line
					(at 40.64 -5.08 180)
					(length 5.08)
					(name "DQ0_B"
						(effects
							(font
								(size 1.27 1.27)
							)
						)
					)
					(number "AA2"
						(effects
							(font
								(size 1.27 1.27)
							)
						)
					)
				)
				(pin bidirectional line
					(at 40.64 -7.62 180)
					(length 5.08)
					(name "DQ1_B"
						(effects
							(font
								(size 1.27 1.27)
							)
						)
					)
					(number "Y2"
						(effects
							(font
								(size 1.27 1.27)
							)
						)
					)
				)
				(pin bidirectional line
					(at 40.64 -10.16 180)
					(length 5.08)
					(name "DQ2_B"
						(effects
							(font
								(size 1.27 1.27)
							)
						)
					)
					(number "V2"
						(effects
							(font
								(size 1.27 1.27)
							)
						)
					)
				)
				(pin bidirectional line
					(at 40.64 -12.7 180)
					(length 5.08)
					(name "DQ3_B"
						(effects
							(font
								(size 1.27 1.27)
							)
						)
					)
					(number "U2"
						(effects
							(font
								(size 1.27 1.27)
							)
						)
					)
				)
				(pin bidirectional line
					(at 40.64 -15.24 180)
					(length 5.08)
					(name "DQ4_B"
						(effects
							(font
								(size 1.27 1.27)
							)
						)
					)
					(number "U4"
						(effects
							(font
								(size 1.27 1.27)
							)
						)
					)
				)
				(pin bidirectional line
					(at 40.64 -17.78 180)
					(length 5.08)
					(name "DQ5_B"
						(effects
							(font
								(size 1.27 1.27)
							)
						)
					)
					(number "V4"
						(effects
							(font
								(size 1.27 1.27)
							)
						)
					)
				)
				(pin bidirectional line
					(at 40.64 -20.32 180)
					(length 5.08)
					(name "DQ6_B"
						(effects
							(font
								(size 1.27 1.27)
							)
						)
					)
					(number "Y4"
						(effects
							(font
								(size 1.27 1.27)
							)
						)
					)
				)
				(pin bidirectional line
					(at 40.64 -22.86 180)
					(length 5.08)
					(name "DQ7_B"
						(effects
							(font
								(size 1.27 1.27)
							)
						)
					)
					(number "AA4"
						(effects
							(font
								(size 1.27 1.27)
							)
						)
					)
				)
				(pin bidirectional line
					(at 40.64 -25.4 180)
					(length 5.08)
					(name "DMI0_B"
						(effects
							(font
								(size 1.27 1.27)
							)
						)
					)
					(number "Y3"
						(effects
							(font
								(size 1.27 1.27)
							)
						)
					)
				)
				(pin bidirectional line
					(at 40.64 -33.02 180)
					(length 5.08)
					(name "DQS1_T_B"
						(effects
							(font
								(size 1.27 1.27)
							)
						)
					)
					(number "W10"
						(effects
							(font
								(size 1.27 1.27)
							)
						)
					)
				)
				(pin bidirectional line
					(at 40.64 -35.56 180)
					(length 5.08)
					(name "DQS1_C_B"
						(effects
							(font
								(size 1.27 1.27)
							)
						)
					)
					(number "V10"
						(effects
							(font
								(size 1.27 1.27)
							)
						)
					)
				)
				(pin bidirectional line
					(at 40.64 -38.1 180)
					(length 5.08)
					(name "DQ8_B"
						(effects
							(font
								(size 1.27 1.27)
							)
						)
					)
					(number "AA11"
						(effects
							(font
								(size 1.27 1.27)
							)
						)
					)
				)
				(pin bidirectional line
					(at 40.64 -40.64 180)
					(length 5.08)
					(name "DQ9_B"
						(effects
							(font
								(size 1.27 1.27)
							)
						)
					)
					(number "Y11"
						(effects
							(font
								(size 1.27 1.27)
							)
						)
					)
				)
				(pin bidirectional line
					(at 40.64 -43.18 180)
					(length 5.08)
					(name "DQ10_B"
						(effects
							(font
								(size 1.27 1.27)
							)
						)
					)
					(number "V11"
						(effects
							(font
								(size 1.27 1.27)
							)
						)
					)
				)
				(pin bidirectional line
					(at 40.64 -45.72 180)
					(length 5.08)
					(name "DQ11_B"
						(effects
							(font
								(size 1.27 1.27)
							)
						)
					)
					(number "U11"
						(effects
							(font
								(size 1.27 1.27)
							)
						)
					)
				)
				(pin bidirectional line
					(at 40.64 -48.26 180)
					(length 5.08)
					(name "DQ12_B"
						(effects
							(font
								(size 1.27 1.27)
							)
						)
					)
					(number "U9"
						(effects
							(font
								(size 1.27 1.27)
							)
						)
					)
				)
				(pin bidirectional line
					(at 40.64 -50.8 180)
					(length 5.08)
					(name "DQ13_B"
						(effects
							(font
								(size 1.27 1.27)
							)
						)
					)
					(number "V9"
						(effects
							(font
								(size 1.27 1.27)
							)
						)
					)
				)
				(pin bidirectional line
					(at 40.64 -53.34 180)
					(length 5.08)
					(name "DQ14_B"
						(effects
							(font
								(size 1.27 1.27)
							)
						)
					)
					(number "Y9"
						(effects
							(font
								(size 1.27 1.27)
							)
						)
					)
				)
				(pin bidirectional line
					(at 40.64 -55.88 180)
					(length 5.08)
					(name "DQ15_B"
						(effects
							(font
								(size 1.27 1.27)
							)
						)
					)
					(number "AA9"
						(effects
							(font
								(size 1.27 1.27)
							)
						)
					)
				)
				(pin bidirectional line
					(at 40.64 -58.42 180)
					(length 5.08)
					(name "DMI1_B"
						(effects
							(font
								(size 1.27 1.27)
							)
						)
					)
					(number "Y10"
						(effects
							(font
								(size 1.27 1.27)
							)
						)
					)
				)
			)
		)
	(symbol "antmicroResistors0402:R_0R_0402"
			(pin_numbers
				(hide yes)
			)
			(pin_names
				(hide yes)
			)
			(exclude_from_sim no)
			(in_bom yes)
			(on_board yes)
			(property "Reference" "R"
				(at 20.32 -5.08 0)
				(effects
					(font
						(size 1.27 1.27)
						(thickness 0.15)
					)
					(justify left bottom)
				)
			)
			(property "Value" "R_0R_0402"
				(at 20.32 -12.7 0)
				(effects
					(font
						(size 1.27 1.27)
						(thickness 0.15)
					)
					(justify left bottom)
					(hide yes)
				)
			)
			(property "Footprint" "antmicro-footprints:R_0402_1005Metric"
				(at 20.32 -15.24 0)
				(effects
					(font
						(size 1.27 1.27)
						(thickness 0.15)
					)
					(justify left bottom)
					(hide yes)
				)
			)
			(property "Datasheet" "https://industrial.panasonic.com/cdbs/www-data/pdf/RDA0000/AOA0000C301.pdf"
				(at 20.32 -17.78 0)
				(effects
					(font
						(size 1.27 1.27)
						(thickness 0.15)
					)
					(justify left bottom)
					(hide yes)
				)
			)
			(property "Description" "0R resistor in 0402 package with unspecified tolerance"
				(at 0 0 0)
				(effects
					(font
						(size 1.27 1.27)
					)
					(hide yes)
				)
			)
			(property "MPN" "ERJ2GE0R00X"
				(at 20.32 -20.32 0)
				(effects
					(font
						(size 1.27 1.27)
						(thickness 0.15)
					)
					(justify left bottom)
					(hide yes)
				)
			)
			(property "Manufacturer" "Panasonic"
				(at 20.32 -22.86 0)
				(effects
					(font
						(size 1.27 1.27)
						(thickness 0.15)
					)
					(justify left bottom)
					(hide yes)
				)
			)
			(property "License" "Apache-2.0"
				(at 20.32 -25.4 0)
				(effects
					(font
						(size 1.27 1.27)
						(thickness 0.15)
					)
					(justify left bottom)
					(hide yes)
				)
			)
			(property "Author" "Antmicro"
				(at 20.32 -27.94 0)
				(effects
					(font
						(size 1.27 1.27)
						(thickness 0.15)
					)
					(justify left bottom)
					(hide yes)
				)
			)
			(property "Val" "0R"
				(at 20.32 -7.62 0)
				(effects
					(font
						(size 1.27 1.27)
						(thickness 0.15)
					)
					(justify left bottom)
				)
			)
			(property "Tolerance" "~"
				(at 20.32 -10.16 0)
				(effects
					(font
						(size 1.27 1.27)
					)
					(justify left bottom)
					(hide yes)
				)
			)
			(property "Current" "1A"
				(at 20.32 -30.48 0)
				(effects
					(font
						(size 1.27 1.27)
						(thickness 0.15)
					)
					(justify left bottom)
					(hide yes)
				)
			)
			(symbol "R_0R_0402_0_1"
				(rectangle
					(start 0.635 0.889)
					(end 4.445 -0.889)
					(stroke
						(width 0.254)
						(type default)
					)
					(fill
						(type none)
					)
				)
			)
			(symbol "R_0R_0402_1_1"
				(pin passive line
					(at 0 0 0)
					(length 0.635)
					(name "~"
						(effects
							(font
								(size 1.27 1.27)
							)
						)
					)
					(number "1"
						(effects
							(font
								(size 1.27 1.27)
							)
						)
					)
				)
				(pin passive line
					(at 5.08 0 180)
					(length 0.635)
					(name "~"
						(effects
							(font
								(size 1.27 1.27)
							)
						)
					)
					(number "2"
						(effects
							(font
								(size 1.27 1.27)
							)
						)
					)
				)
			)
		)
	(symbol "antmicroResistors0402:R_10k_0402"
			(pin_numbers
				(hide yes)
			)
			(pin_names
				(hide yes)
			)
			(exclude_from_sim no)
			(in_bom yes)
			(on_board yes)
			(property "Reference" "R"
				(at 20.32 -5.08 0)
				(effects
					(font
						(size 1.27 1.27)
						(thickness 0.15)
					)
					(justify left bottom)
				)
			)
			(property "Value" "R_10k_0402"
				(at 20.32 -12.7 0)
				(effects
					(font
						(size 1.27 1.27)
						(thickness 0.15)
					)
					(justify left bottom)
					(hide yes)
				)
			)
			(property "Footprint" "antmicro-footprints:R_0402_1005Metric"
				(at 20.32 -15.24 0)
				(effects
					(font
						(size 1.27 1.27)
						(thickness 0.15)
					)
					(justify left bottom)
					(hide yes)
				)
			)
			(property "Datasheet" "https://www.bourns.com/docs/product-datasheets/cr.pdf"
				(at 20.32 -17.78 0)
				(effects
					(font
						(size 1.27 1.27)
						(thickness 0.15)
					)
					(justify left bottom)
					(hide yes)
				)
			)
			(property "Description" "10k resistor in 0402 package with 1% tolerance"
				(at 0 0 0)
				(effects
					(font
						(size 1.27 1.27)
					)
					(hide yes)
				)
			)
			(property "MPN" "CR0402-FX-1002GLF"
				(at 20.32 -20.32 0)
				(effects
					(font
						(size 1.27 1.27)
						(thickness 0.15)
					)
					(justify left bottom)
					(hide yes)
				)
			)
			(property "Manufacturer" "Bourns"
				(at 20.32 -22.86 0)
				(effects
					(font
						(size 1.27 1.27)
						(thickness 0.15)
					)
					(justify left bottom)
					(hide yes)
				)
			)
			(property "License" "Apache-2.0"
				(at 20.32 -25.4 0)
				(effects
					(font
						(size 1.27 1.27)
						(thickness 0.15)
					)
					(justify left bottom)
					(hide yes)
				)
			)
			(property "Author" "Antmicro"
				(at 20.32 -27.94 0)
				(effects
					(font
						(size 1.27 1.27)
						(thickness 0.15)
					)
					(justify left bottom)
					(hide yes)
				)
			)
			(property "Val" "10k"
				(at 20.32 -7.62 0)
				(effects
					(font
						(size 1.27 1.27)
						(thickness 0.15)
					)
					(justify left bottom)
				)
			)
			(property "Tolerance" "1%"
				(at 20.32 -10.16 0)
				(effects
					(font
						(size 1.27 1.27)
					)
					(justify left bottom)
					(hide yes)
				)
			)
			(symbol "R_10k_0402_0_1"
				(rectangle
					(start 0.635 0.889)
					(end 4.445 -0.889)
					(stroke
						(width 0.254)
						(type default)
					)
					(fill
						(type none)
					)
				)
			)
			(symbol "R_10k_0402_1_1"
				(pin passive line
					(at 0 0 0)
					(length 0.635)
					(name "~"
						(effects
							(font
								(size 1.27 1.27)
							)
						)
					)
					(number "1"
						(effects
							(font
								(size 1.27 1.27)
							)
						)
					)
				)
				(pin passive line
					(at 5.08 0 180)
					(length 0.635)
					(name "~"
						(effects
							(font
								(size 1.27 1.27)
							)
						)
					)
					(number "2"
						(effects
							(font
								(size 1.27 1.27)
							)
						)
					)
				)
			)
		)
	(symbol "antmicroResistors0402:R_220R_0402"
			(pin_numbers
				(hide yes)
			)
			(pin_names
				(hide yes)
			)
			(exclude_from_sim no)
			(in_bom yes)
			(on_board yes)
			(property "Reference" "R"
				(at 20.32 -5.08 0)
				(effects
					(font
						(size 1.27 1.27)
						(thickness 0.15)
					)
					(justify left bottom)
				)
			)
			(property "Value" "R_220R_0402"
				(at 20.32 -12.7 0)
				(effects
					(font
						(size 1.27 1.27)
						(thickness 0.15)
					)
					(justify left bottom)
					(hide yes)
				)
			)
			(property "Footprint" "antmicro-footprints:R_0402_1005Metric"
				(at 20.32 -15.24 0)
				(effects
					(font
						(size 1.27 1.27)
						(thickness 0.15)
					)
					(justify left bottom)
					(hide yes)
				)
			)
			(property "Datasheet" "https://www.bourns.com/docs/product-datasheets/cr.pdf"
				(at 20.32 -17.78 0)
				(effects
					(font
						(size 1.27 1.27)
						(thickness 0.15)
					)
					(justify left bottom)
					(hide yes)
				)
			)
			(property "Description" "220R resistor in 0402 package with 1% tolerance"
				(at 0 0 0)
				(effects
					(font
						(size 1.27 1.27)
					)
					(hide yes)
				)
			)
			(property "MPN" "CR0402-FX-2200GLF"
				(at 20.32 -20.32 0)
				(effects
					(font
						(size 1.27 1.27)
						(thickness 0.15)
					)
					(justify left bottom)
					(hide yes)
				)
			)
			(property "Manufacturer" "Bourns"
				(at 20.32 -22.86 0)
				(effects
					(font
						(size 1.27 1.27)
						(thickness 0.15)
					)
					(justify left bottom)
					(hide yes)
				)
			)
			(property "License" "Apache-2.0"
				(at 20.32 -25.4 0)
				(effects
					(font
						(size 1.27 1.27)
						(thickness 0.15)
					)
					(justify left bottom)
					(hide yes)
				)
			)
			(property "Author" "Antmicro"
				(at 20.32 -27.94 0)
				(effects
					(font
						(size 1.27 1.27)
						(thickness 0.15)
					)
					(justify left bottom)
					(hide yes)
				)
			)
			(property "Val" "220R"
				(at 20.32 -7.62 0)
				(effects
					(font
						(size 1.27 1.27)
						(thickness 0.15)
					)
					(justify left bottom)
				)
			)
			(property "Tolerance" "1%"
				(at 20.32 -10.16 0)
				(effects
					(font
						(size 1.27 1.27)
					)
					(justify left bottom)
					(hide yes)
				)
			)
			(symbol "R_220R_0402_0_1"
				(rectangle
					(start 0.635 0.889)
					(end 4.445 -0.889)
					(stroke
						(width 0.254)
						(type default)
					)
					(fill
						(type none)
					)
				)
			)
			(symbol "R_220R_0402_1_1"
				(pin passive line
					(at 0 0 0)
					(length 0.635)
					(name "~"
						(effects
							(font
								(size 1.27 1.27)
							)
						)
					)
					(number "1"
						(effects
							(font
								(size 1.27 1.27)
							)
						)
					)
				)
				(pin passive line
					(at 5.08 0 180)
					(length 0.635)
					(name "~"
						(effects
							(font
								(size 1.27 1.27)
							)
						)
					)
					(number "2"
						(effects
							(font
								(size 1.27 1.27)
							)
						)
					)
				)
			)
		)
	(symbol "antmicroResistors0402:R_240R_0402"
			(pin_numbers
				(hide yes)
			)
			(pin_names
				(hide yes)
			)
			(exclude_from_sim no)
			(in_bom yes)
			(on_board yes)
			(property "Reference" "R"
				(at 20.32 -5.08 0)
				(effects
					(font
						(size 1.27 1.27)
						(thickness 0.15)
					)
					(justify left bottom)
				)
			)
			(property "Value" "R_240R_0402"
				(at 20.32 -12.7 0)
				(effects
					(font
						(size 1.27 1.27)
						(thickness 0.15)
					)
					(justify left bottom)
					(hide yes)
				)
			)
			(property "Footprint" "antmicro-footprints:R_0402_1005Metric"
				(at 20.32 -15.24 0)
				(effects
					(font
						(size 1.27 1.27)
						(thickness 0.15)
					)
					(justify left bottom)
					(hide yes)
				)
			)
			(property "Datasheet" "https://www.bourns.com/docs/product-datasheets/cr.pdf"
				(at 20.32 -17.78 0)
				(effects
					(font
						(size 1.27 1.27)
						(thickness 0.15)
					)
					(justify left bottom)
					(hide yes)
				)
			)
			(property "Description" "240R resistor in 0402 package with 1% tolerance"
				(at 0 0 0)
				(effects
					(font
						(size 1.27 1.27)
					)
					(hide yes)
				)
			)
			(property "MPN" "CR0402-FX-2400GLF"
				(at 20.32 -20.32 0)
				(effects
					(font
						(size 1.27 1.27)
						(thickness 0.15)
					)
					(justify left bottom)
					(hide yes)
				)
			)
			(property "Manufacturer" "Bourns"
				(at 20.32 -22.86 0)
				(effects
					(font
						(size 1.27 1.27)
						(thickness 0.15)
					)
					(justify left bottom)
					(hide yes)
				)
			)
			(property "License" "Apache-2.0"
				(at 20.32 -25.4 0)
				(effects
					(font
						(size 1.27 1.27)
						(thickness 0.15)
					)
					(justify left bottom)
					(hide yes)
				)
			)
			(property "Author" "Antmicro"
				(at 20.32 -27.94 0)
				(effects
					(font
						(size 1.27 1.27)
						(thickness 0.15)
					)
					(justify left bottom)
					(hide yes)
				)
			)
			(property "Val" "240R"
				(at 20.32 -7.62 0)
				(effects
					(font
						(size 1.27 1.27)
						(thickness 0.15)
					)
					(justify left bottom)
				)
			)
			(property "Tolerance" "1%"
				(at 20.32 -10.16 0)
				(effects
					(font
						(size 1.27 1.27)
					)
					(justify left bottom)
					(hide yes)
				)
			)
			(symbol "R_240R_0402_0_1"
				(rectangle
					(start 0.635 0.889)
					(end 4.445 -0.889)
					(stroke
						(width 0.254)
						(type default)
					)
					(fill
						(type none)
					)
				)
			)
			(symbol "R_240R_0402_1_1"
				(pin passive line
					(at 0 0 0)
					(length 0.635)
					(name "~"
						(effects
							(font
								(size 1.27 1.27)
							)
						)
					)
					(number "1"
						(effects
							(font
								(size 1.27 1.27)
							)
						)
					)
				)
				(pin passive line
					(at 5.08 0 180)
					(length 0.635)
					(name "~"
						(effects
							(font
								(size 1.27 1.27)
							)
						)
					)
					(number "2"
						(effects
							(font
								(size 1.27 1.27)
							)
						)
					)
				)
			)
		)
	(symbol "antmicroTestPoints:TP_0.75mm_SMD"
			(pin_numbers
				(hide yes)
			)
			(pin_names
				(hide yes)
			)
			(exclude_from_sim no)
			(in_bom yes)
			(on_board yes)
			(property "Reference" "TP"
				(at 17.78 -5.08 0)
				(effects
					(font
						(size 1.27 1.27)
						(thickness 0.15)
					)
					(justify left bottom)
				)
			)
			(property "Value" "TP_0.75mm_SMD"
				(at 17.78 -7.62 0)
				(effects
					(font
						(size 1.27 1.27)
						(thickness 0.15)
					)
					(justify left bottom)
					(hide yes)
				)
			)
			(property "Footprint" "antmicro-footprints:TP_SMD_0.75mm"
				(at 17.78 -10.16 0)
				(effects
					(font
						(size 1.27 1.27)
						(thickness 0.15)
					)
					(justify left bottom)
					(hide yes)
				)
			)
			(property "Datasheet" ""
				(at 17.78 -12.7 0)
				(effects
					(font
						(size 1.27 1.27)
						(thickness 0.15)
					)
					(justify left bottom)
					(hide yes)
				)
			)
			(property "Description" "Test Point 0.75mm"
				(at 0 0 0)
				(effects
					(font
						(size 1.27 1.27)
					)
					(hide yes)
				)
			)
			(property "MPN" ""
				(at 17.78 -15.24 0)
				(effects
					(font
						(size 1.27 1.27)
						(thickness 0.15)
					)
					(justify left bottom)
					(hide yes)
				)
			)
			(property "Manufacturer" ""
				(at 17.78 -17.78 0)
				(effects
					(font
						(size 1.27 1.27)
						(thickness 0.15)
					)
					(justify left bottom)
					(hide yes)
				)
			)
			(property "Author" "Antmicro"
				(at 17.78 -20.32 0)
				(effects
					(font
						(size 1.27 1.27)
						(thickness 0.15)
					)
					(justify left bottom)
					(hide yes)
				)
			)
			(property "License" "Apache-2.0"
				(at 17.78 -22.86 0)
				(effects
					(font
						(size 1.27 1.27)
						(thickness 0.15)
					)
					(justify left bottom)
					(hide yes)
				)
			)
			(symbol "TP_0.75mm_SMD_1_1"
				(circle
					(center 3.175 0)
					(radius 0.635)
					(stroke
						(width 0.254)
						(type default)
					)
					(fill
						(type none)
					)
				)
				(pin passive line
					(at 0 0 0)
					(length 2.54)
					(name "1"
						(effects
							(font
								(size 1.27 1.27)
							)
						)
					)
					(number "1"
						(effects
							(font
								(size 1.27 1.27)
							)
						)
					)
				)
			)
		)
	(symbol "antmicropower:GND"
			(power)
			(pin_names
				(offset 0)
			)
			(exclude_from_sim no)
			(in_bom yes)
			(on_board yes)
			(property "Reference" "#PWR"
				(at 0 -6.35 0)
				(effects
					(font
						(size 1.27 1.27)
					)
					(hide yes)
				)
			)
			(property "Value" "GND"
				(at 0 -3.81 0)
				(effects
					(font
						(size 1.27 1.27)
					)
				)
			)
			(property "Footprint" ""
				(at 0 0 0)
				(effects
					(font
						(size 1.27 1.27)
					)
					(hide yes)
				)
			)
			(property "Datasheet" ""
				(at 0 0 0)
				(effects
					(font
						(size 1.27 1.27)
					)
					(hide yes)
				)
			)
			(property "Description" ""
				(at 0 0 0)
				(effects
					(font
						(size 1.27 1.27)
					)
					(hide yes)
				)
			)
			(symbol "GND_0_1"
				(polyline
					(pts
						(xy 0 0) (xy 0 -1.27) (xy 1.27 -1.27) (xy 0 -2.54) (xy -1.27 -1.27) (xy 0 -1.27)
					)
					(stroke
						(width 0)
						(type default)
					)
					(fill
						(type none)
					)
				)
			)
			(symbol "GND_1_1"
				(pin power_in line
					(at 0 0 270)
					(length 0)
					(hide yes)
					(name "GND"
						(effects
							(font
								(size 1.27 1.27)
							)
						)
					)
					(number "1"
						(effects
							(font
								(size 1.27 1.27)
							)
						)
					)
				)
			)
		)
	(symbol "antmicropower:PWR_FLAG"
			(power)
			(pin_numbers
				(hide yes)
			)
			(pin_names
				(offset 0)
				(hide yes)
			)
			(exclude_from_sim no)
			(in_bom yes)
			(on_board yes)
			(property "Reference" "#FLG"
				(at 0 1.905 0)
				(effects
					(font
						(size 1.27 1.27)
					)
					(hide yes)
				)
			)
			(property "Value" "PWR_FLAG"
				(at 0 3.81 0)
				(effects
					(font
						(size 1.27 1.27)
					)
				)
			)
			(property "Footprint" ""
				(at 0 0 0)
				(effects
					(font
						(size 1.27 1.27)
					)
					(hide yes)
				)
			)
			(property "Datasheet" ""
				(at 0 0 0)
				(effects
					(font
						(size 1.27 1.27)
					)
					(hide yes)
				)
			)
			(property "Description" ""
				(at 0 0 0)
				(effects
					(font
						(size 1.27 1.27)
					)
					(hide yes)
				)
			)
			(symbol "PWR_FLAG_0_0"
				(pin power_out line
					(at 0 0 90)
					(length 0)
					(name "pwr"
						(effects
							(font
								(size 1.27 1.27)
							)
						)
					)
					(number "1"
						(effects
							(font
								(size 1.27 1.27)
							)
						)
					)
				)
			)
			(symbol "PWR_FLAG_0_1"
				(polyline
					(pts
						(xy 0 0) (xy 0 1.27) (xy -1.016 1.905) (xy 0 2.54) (xy 1.016 1.905) (xy 0 1.27)
					)
					(stroke
						(width 0)
						(type default)
					)
					(fill
						(type none)
					)
				)
			)
		)
	(symbol "lpddr4-testbed:Edge_Conn_Bus_DDR4"
			(exclude_from_sim no)
			(in_bom no)
			(on_board yes)
			(property "Reference" "J"
				(at 36.83 0 0)
				(effects
					(font
						(size 1.27 1.27)
						(thickness 0.15)
					)
					(justify left bottom)
				)
			)
			(property "Value" "Edge_Conn_Bus_DDR4"
				(at 36.83 -2.54 0)
				(effects
					(font
						(size 1.27 1.27)
						(thickness 0.15)
					)
					(justify left bottom)
				)
			)
			(property "Footprint" "lpddr4-testbed-footprints:Edge_Conn_Bus_DDR4"
				(at 36.83 -5.08 0)
				(effects
					(font
						(size 1.27 1.27)
						(thickness 0.15)
					)
					(justify left bottom)
					(hide yes)
				)
			)
			(property "Datasheet" ""
				(at 36.83 -12.7 0)
				(effects
					(font
						(size 1.27 1.27)
						(thickness 0.15)
					)
					(justify left bottom)
					(hide yes)
				)
			)
			(property "Description" "DDR SO-DIMM PCB Edge"
				(at 0 0 0)
				(effects
					(font
						(size 1.27 1.27)
					)
					(hide yes)
				)
			)
			(property "MPN" ""
				(at 36.83 -6.35 0)
				(effects
					(font
						(size 1.27 1.27)
					)
					(justify left)
					(hide yes)
				)
			)
			(property "Manufacturer" ""
				(at 36.83 -8.89 0)
				(effects
					(font
						(size 1.27 1.27)
					)
					(justify left)
					(hide yes)
				)
			)
			(property "Author" "Antmicro"
				(at 36.83 -15.24 0)
				(effects
					(font
						(size 1.27 1.27)
						(thickness 0.15)
					)
					(justify left bottom)
					(hide yes)
				)
			)
			(property "License" "Apache-2.0"
				(at 36.83 -17.78 0)
				(effects
					(font
						(size 1.27 1.27)
						(thickness 0.15)
					)
					(justify left bottom)
					(hide yes)
				)
			)
			(property "ki_locked" ""
				(at 0 0 0)
				(effects
					(font
						(size 1.27 1.27)
					)
				)
			)
			(property "ki_keywords" "EDGE, CONNECTOR"
				(at 0 0 0)
				(effects
					(font
						(size 1.27 1.27)
					)
					(hide yes)
				)
			)
			(symbol "Edge_Conn_Bus_DDR4_1_1"
				(rectangle
					(start 3.81 2.54)
					(end 19.05 -165.1)
					(stroke
						(width 0.254)
						(type default)
					)
					(fill
						(type background)
					)
				)
				(pin passive line
					(at 0 0 0)
					(length 3.81)
					(name "1"
						(effects
							(font
								(size 1.27 1.27)
							)
						)
					)
					(number "1"
						(effects
							(font
								(size 1.27 1.27)
							)
						)
					)
				)
				(pin passive line
					(at 0 -2.54 0)
					(length 3.81)
					(name "3"
						(effects
							(font
								(size 1.27 1.27)
							)
						)
					)
					(number "3"
						(effects
							(font
								(size 1.27 1.27)
							)
						)
					)
				)
				(pin passive line
					(at 0 -5.08 0)
					(length 3.81)
					(name "5"
						(effects
							(font
								(size 1.27 1.27)
							)
						)
					)
					(number "5"
						(effects
							(font
								(size 1.27 1.27)
							)
						)
					)
				)
				(pin passive line
					(at 0 -7.62 0)
					(length 3.81)
					(name "7"
						(effects
							(font
								(size 1.27 1.27)
							)
						)
					)
					(number "7"
						(effects
							(font
								(size 1.27 1.27)
							)
						)
					)
				)
				(pin passive line
					(at 0 -10.16 0)
					(length 3.81)
					(name "9"
						(effects
							(font
								(size 1.27 1.27)
							)
						)
					)
					(number "9"
						(effects
							(font
								(size 1.27 1.27)
							)
						)
					)
				)
				(pin passive line
					(at 0 -12.7 0)
					(length 3.81)
					(name "11"
						(effects
							(font
								(size 1.27 1.27)
							)
						)
					)
					(number "11"
						(effects
							(font
								(size 1.27 1.27)
							)
						)
					)
				)
				(pin passive line
					(at 0 -15.24 0)
					(length 3.81)
					(name "13"
						(effects
							(font
								(size 1.27 1.27)
							)
						)
					)
					(number "13"
						(effects
							(font
								(size 1.27 1.27)
							)
						)
					)
				)
				(pin passive line
					(at 0 -17.78 0)
					(length 3.81)
					(name "15"
						(effects
							(font
								(size 1.27 1.27)
							)
						)
					)
					(number "15"
						(effects
							(font
								(size 1.27 1.27)
							)
						)
					)
				)
				(pin passive line
					(at 0 -20.32 0)
					(length 3.81)
					(name "17"
						(effects
							(font
								(size 1.27 1.27)
							)
						)
					)
					(number "17"
						(effects
							(font
								(size 1.27 1.27)
							)
						)
					)
				)
				(pin passive line
					(at 0 -22.86 0)
					(length 3.81)
					(name "19"
						(effects
							(font
								(size 1.27 1.27)
							)
						)
					)
					(number "19"
						(effects
							(font
								(size 1.27 1.27)
							)
						)
					)
				)
				(pin passive line
					(at 0 -25.4 0)
					(length 3.81)
					(name "21"
						(effects
							(font
								(size 1.27 1.27)
							)
						)
					)
					(number "21"
						(effects
							(font
								(size 1.27 1.27)
							)
						)
					)
				)
				(pin passive line
					(at 0 -27.94 0)
					(length 3.81)
					(name "23"
						(effects
							(font
								(size 1.27 1.27)
							)
						)
					)
					(number "23"
						(effects
							(font
								(size 1.27 1.27)
							)
						)
					)
				)
				(pin passive line
					(at 0 -30.48 0)
					(length 3.81)
					(name "25"
						(effects
							(font
								(size 1.27 1.27)
							)
						)
					)
					(number "25"
						(effects
							(font
								(size 1.27 1.27)
							)
						)
					)
				)
				(pin passive line
					(at 0 -33.02 0)
					(length 3.81)
					(name "27"
						(effects
							(font
								(size 1.27 1.27)
							)
						)
					)
					(number "27"
						(effects
							(font
								(size 1.27 1.27)
							)
						)
					)
				)
				(pin passive line
					(at 0 -35.56 0)
					(length 3.81)
					(name "29"
						(effects
							(font
								(size 1.27 1.27)
							)
						)
					)
					(number "29"
						(effects
							(font
								(size 1.27 1.27)
							)
						)
					)
				)
				(pin passive line
					(at 0 -38.1 0)
					(length 3.81)
					(name "31"
						(effects
							(font
								(size 1.27 1.27)
							)
						)
					)
					(number "31"
						(effects
							(font
								(size 1.27 1.27)
							)
						)
					)
				)
				(pin passive line
					(at 0 -40.64 0)
					(length 3.81)
					(name "33"
						(effects
							(font
								(size 1.27 1.27)
							)
						)
					)
					(number "33"
						(effects
							(font
								(size 1.27 1.27)
							)
						)
					)
				)
				(pin passive line
					(at 0 -43.18 0)
					(length 3.81)
					(name "35"
						(effects
							(font
								(size 1.27 1.27)
							)
						)
					)
					(number "35"
						(effects
							(font
								(size 1.27 1.27)
							)
						)
					)
				)
				(pin passive line
					(at 0 -45.72 0)
					(length 3.81)
					(name "37"
						(effects
							(font
								(size 1.27 1.27)
							)
						)
					)
					(number "37"
						(effects
							(font
								(size 1.27 1.27)
							)
						)
					)
				)
				(pin passive line
					(at 0 -48.26 0)
					(length 3.81)
					(name "39"
						(effects
							(font
								(size 1.27 1.27)
							)
						)
					)
					(number "39"
						(effects
							(font
								(size 1.27 1.27)
							)
						)
					)
				)
				(pin passive line
					(at 0 -50.8 0)
					(length 3.81)
					(name "41"
						(effects
							(font
								(size 1.27 1.27)
							)
						)
					)
					(number "41"
						(effects
							(font
								(size 1.27 1.27)
							)
						)
					)
				)
				(pin passive line
					(at 0 -53.34 0)
					(length 3.81)
					(name "43"
						(effects
							(font
								(size 1.27 1.27)
							)
						)
					)
					(number "43"
						(effects
							(font
								(size 1.27 1.27)
							)
						)
					)
				)
				(pin passive line
					(at 0 -55.88 0)
					(length 3.81)
					(name "45"
						(effects
							(font
								(size 1.27 1.27)
							)
						)
					)
					(number "45"
						(effects
							(font
								(size 1.27 1.27)
							)
						)
					)
				)
				(pin passive line
					(at 0 -58.42 0)
					(length 3.81)
					(name "47"
						(effects
							(font
								(size 1.27 1.27)
							)
						)
					)
					(number "47"
						(effects
							(font
								(size 1.27 1.27)
							)
						)
					)
				)
				(pin passive line
					(at 0 -60.96 0)
					(length 3.81)
					(name "49"
						(effects
							(font
								(size 1.27 1.27)
							)
						)
					)
					(number "49"
						(effects
							(font
								(size 1.27 1.27)
							)
						)
					)
				)
				(pin passive line
					(at 0 -63.5 0)
					(length 3.81)
					(name "51"
						(effects
							(font
								(size 1.27 1.27)
							)
						)
					)
					(number "51"
						(effects
							(font
								(size 1.27 1.27)
							)
						)
					)
				)
				(pin passive line
					(at 0 -66.04 0)
					(length 3.81)
					(name "53"
						(effects
							(font
								(size 1.27 1.27)
							)
						)
					)
					(number "53"
						(effects
							(font
								(size 1.27 1.27)
							)
						)
					)
				)
				(pin passive line
					(at 0 -68.58 0)
					(length 3.81)
					(name "55"
						(effects
							(font
								(size 1.27 1.27)
							)
						)
					)
					(number "55"
						(effects
							(font
								(size 1.27 1.27)
							)
						)
					)
				)
				(pin passive line
					(at 0 -71.12 0)
					(length 3.81)
					(name "57"
						(effects
							(font
								(size 1.27 1.27)
							)
						)
					)
					(number "57"
						(effects
							(font
								(size 1.27 1.27)
							)
						)
					)
				)
				(pin passive line
					(at 0 -73.66 0)
					(length 3.81)
					(name "59"
						(effects
							(font
								(size 1.27 1.27)
							)
						)
					)
					(number "59"
						(effects
							(font
								(size 1.27 1.27)
							)
						)
					)
				)
				(pin passive line
					(at 0 -76.2 0)
					(length 3.81)
					(name "61"
						(effects
							(font
								(size 1.27 1.27)
							)
						)
					)
					(number "61"
						(effects
							(font
								(size 1.27 1.27)
							)
						)
					)
				)
				(pin passive line
					(at 0 -78.74 0)
					(length 3.81)
					(name "63"
						(effects
							(font
								(size 1.27 1.27)
							)
						)
					)
					(number "63"
						(effects
							(font
								(size 1.27 1.27)
							)
						)
					)
				)
				(pin passive line
					(at 0 -81.28 0)
					(length 3.81)
					(name "65"
						(effects
							(font
								(size 1.27 1.27)
							)
						)
					)
					(number "65"
						(effects
							(font
								(size 1.27 1.27)
							)
						)
					)
				)
				(pin passive line
					(at 0 -83.82 0)
					(length 3.81)
					(name "67"
						(effects
							(font
								(size 1.27 1.27)
							)
						)
					)
					(number "67"
						(effects
							(font
								(size 1.27 1.27)
							)
						)
					)
				)
				(pin passive line
					(at 0 -86.36 0)
					(length 3.81)
					(name "69"
						(effects
							(font
								(size 1.27 1.27)
							)
						)
					)
					(number "69"
						(effects
							(font
								(size 1.27 1.27)
							)
						)
					)
				)
				(pin passive line
					(at 0 -88.9 0)
					(length 3.81)
					(name "71"
						(effects
							(font
								(size 1.27 1.27)
							)
						)
					)
					(number "71"
						(effects
							(font
								(size 1.27 1.27)
							)
						)
					)
				)
				(pin passive line
					(at 0 -91.44 0)
					(length 3.81)
					(name "73"
						(effects
							(font
								(size 1.27 1.27)
							)
						)
					)
					(number "73"
						(effects
							(font
								(size 1.27 1.27)
							)
						)
					)
				)
				(pin passive line
					(at 0 -93.98 0)
					(length 3.81)
					(name "75"
						(effects
							(font
								(size 1.27 1.27)
							)
						)
					)
					(number "75"
						(effects
							(font
								(size 1.27 1.27)
							)
						)
					)
				)
				(pin passive line
					(at 0 -96.52 0)
					(length 3.81)
					(name "77"
						(effects
							(font
								(size 1.27 1.27)
							)
						)
					)
					(number "77"
						(effects
							(font
								(size 1.27 1.27)
							)
						)
					)
				)
				(pin passive line
					(at 0 -99.06 0)
					(length 3.81)
					(name "79"
						(effects
							(font
								(size 1.27 1.27)
							)
						)
					)
					(number "79"
						(effects
							(font
								(size 1.27 1.27)
							)
						)
					)
				)
				(pin passive line
					(at 0 -101.6 0)
					(length 3.81)
					(name "81"
						(effects
							(font
								(size 1.27 1.27)
							)
						)
					)
					(number "81"
						(effects
							(font
								(size 1.27 1.27)
							)
						)
					)
				)
				(pin passive line
					(at 0 -104.14 0)
					(length 3.81)
					(name "83"
						(effects
							(font
								(size 1.27 1.27)
							)
						)
					)
					(number "83"
						(effects
							(font
								(size 1.27 1.27)
							)
						)
					)
				)
				(pin passive line
					(at 0 -106.68 0)
					(length 3.81)
					(name "85"
						(effects
							(font
								(size 1.27 1.27)
							)
						)
					)
					(number "85"
						(effects
							(font
								(size 1.27 1.27)
							)
						)
					)
				)
				(pin passive line
					(at 0 -109.22 0)
					(length 3.81)
					(name "87"
						(effects
							(font
								(size 1.27 1.27)
							)
						)
					)
					(number "87"
						(effects
							(font
								(size 1.27 1.27)
							)
						)
					)
				)
				(pin passive line
					(at 0 -111.76 0)
					(length 3.81)
					(name "89"
						(effects
							(font
								(size 1.27 1.27)
							)
						)
					)
					(number "89"
						(effects
							(font
								(size 1.27 1.27)
							)
						)
					)
				)
				(pin passive line
					(at 0 -114.3 0)
					(length 3.81)
					(name "91"
						(effects
							(font
								(size 1.27 1.27)
							)
						)
					)
					(number "91"
						(effects
							(font
								(size 1.27 1.27)
							)
						)
					)
				)
				(pin passive line
					(at 0 -116.84 0)
					(length 3.81)
					(name "93"
						(effects
							(font
								(size 1.27 1.27)
							)
						)
					)
					(number "93"
						(effects
							(font
								(size 1.27 1.27)
							)
						)
					)
				)
				(pin passive line
					(at 0 -119.38 0)
					(length 3.81)
					(name "95"
						(effects
							(font
								(size 1.27 1.27)
							)
						)
					)
					(number "95"
						(effects
							(font
								(size 1.27 1.27)
							)
						)
					)
				)
				(pin passive line
					(at 0 -121.92 0)
					(length 3.81)
					(name "97"
						(effects
							(font
								(size 1.27 1.27)
							)
						)
					)
					(number "97"
						(effects
							(font
								(size 1.27 1.27)
							)
						)
					)
				)
				(pin passive line
					(at 0 -124.46 0)
					(length 3.81)
					(name "99"
						(effects
							(font
								(size 1.27 1.27)
							)
						)
					)
					(number "99"
						(effects
							(font
								(size 1.27 1.27)
							)
						)
					)
				)
				(pin passive line
					(at 0 -127 0)
					(length 3.81)
					(name "101"
						(effects
							(font
								(size 1.27 1.27)
							)
						)
					)
					(number "101"
						(effects
							(font
								(size 1.27 1.27)
							)
						)
					)
				)
				(pin passive line
					(at 0 -129.54 0)
					(length 3.81)
					(name "103"
						(effects
							(font
								(size 1.27 1.27)
							)
						)
					)
					(number "103"
						(effects
							(font
								(size 1.27 1.27)
							)
						)
					)
				)
				(pin passive line
					(at 0 -132.08 0)
					(length 3.81)
					(name "105"
						(effects
							(font
								(size 1.27 1.27)
							)
						)
					)
					(number "105"
						(effects
							(font
								(size 1.27 1.27)
							)
						)
					)
				)
				(pin passive line
					(at 0 -134.62 0)
					(length 3.81)
					(name "107"
						(effects
							(font
								(size 1.27 1.27)
							)
						)
					)
					(number "107"
						(effects
							(font
								(size 1.27 1.27)
							)
						)
					)
				)
				(pin passive line
					(at 0 -137.16 0)
					(length 3.81)
					(name "109"
						(effects
							(font
								(size 1.27 1.27)
							)
						)
					)
					(number "109"
						(effects
							(font
								(size 1.27 1.27)
							)
						)
					)
				)
				(pin passive line
					(at 0 -139.7 0)
					(length 3.81)
					(name "111"
						(effects
							(font
								(size 1.27 1.27)
							)
						)
					)
					(number "111"
						(effects
							(font
								(size 1.27 1.27)
							)
						)
					)
				)
				(pin passive line
					(at 0 -142.24 0)
					(length 3.81)
					(name "113"
						(effects
							(font
								(size 1.27 1.27)
							)
						)
					)
					(number "113"
						(effects
							(font
								(size 1.27 1.27)
							)
						)
					)
				)
				(pin passive line
					(at 0 -144.78 0)
					(length 3.81)
					(name "115"
						(effects
							(font
								(size 1.27 1.27)
							)
						)
					)
					(number "115"
						(effects
							(font
								(size 1.27 1.27)
							)
						)
					)
				)
				(pin passive line
					(at 0 -147.32 0)
					(length 3.81)
					(name "117"
						(effects
							(font
								(size 1.27 1.27)
							)
						)
					)
					(number "117"
						(effects
							(font
								(size 1.27 1.27)
							)
						)
					)
				)
				(pin passive line
					(at 0 -149.86 0)
					(length 3.81)
					(name "119"
						(effects
							(font
								(size 1.27 1.27)
							)
						)
					)
					(number "119"
						(effects
							(font
								(size 1.27 1.27)
							)
						)
					)
				)
				(pin passive line
					(at 0 -152.4 0)
					(length 3.81)
					(name "121"
						(effects
							(font
								(size 1.27 1.27)
							)
						)
					)
					(number "121"
						(effects
							(font
								(size 1.27 1.27)
							)
						)
					)
				)
				(pin passive line
					(at 0 -154.94 0)
					(length 3.81)
					(name "123"
						(effects
							(font
								(size 1.27 1.27)
							)
						)
					)
					(number "123"
						(effects
							(font
								(size 1.27 1.27)
							)
						)
					)
				)
				(pin passive line
					(at 0 -157.48 0)
					(length 3.81)
					(name "125"
						(effects
							(font
								(size 1.27 1.27)
							)
						)
					)
					(number "125"
						(effects
							(font
								(size 1.27 1.27)
							)
						)
					)
				)
				(pin passive line
					(at 0 -160.02 0)
					(length 3.81)
					(name "127"
						(effects
							(font
								(size 1.27 1.27)
							)
						)
					)
					(number "127"
						(effects
							(font
								(size 1.27 1.27)
							)
						)
					)
				)
				(pin passive line
					(at 0 -162.56 0)
					(length 3.81)
					(name "129"
						(effects
							(font
								(size 1.27 1.27)
							)
						)
					)
					(number "129"
						(effects
							(font
								(size 1.27 1.27)
							)
						)
					)
				)
				(pin passive line
					(at 22.86 0 180)
					(length 3.81)
					(name "2"
						(effects
							(font
								(size 1.27 1.27)
							)
						)
					)
					(number "2"
						(effects
							(font
								(size 1.27 1.27)
							)
						)
					)
				)
				(pin passive line
					(at 22.86 -2.54 180)
					(length 3.81)
					(name "4"
						(effects
							(font
								(size 1.27 1.27)
							)
						)
					)
					(number "4"
						(effects
							(font
								(size 1.27 1.27)
							)
						)
					)
				)
				(pin passive line
					(at 22.86 -5.08 180)
					(length 3.81)
					(name "6"
						(effects
							(font
								(size 1.27 1.27)
							)
						)
					)
					(number "6"
						(effects
							(font
								(size 1.27 1.27)
							)
						)
					)
				)
				(pin passive line
					(at 22.86 -7.62 180)
					(length 3.81)
					(name "8"
						(effects
							(font
								(size 1.27 1.27)
							)
						)
					)
					(number "8"
						(effects
							(font
								(size 1.27 1.27)
							)
						)
					)
				)
				(pin passive line
					(at 22.86 -10.16 180)
					(length 3.81)
					(name "10"
						(effects
							(font
								(size 1.27 1.27)
							)
						)
					)
					(number "10"
						(effects
							(font
								(size 1.27 1.27)
							)
						)
					)
				)
				(pin passive line
					(at 22.86 -12.7 180)
					(length 3.81)
					(name "12"
						(effects
							(font
								(size 1.27 1.27)
							)
						)
					)
					(number "12"
						(effects
							(font
								(size 1.27 1.27)
							)
						)
					)
				)
				(pin passive line
					(at 22.86 -15.24 180)
					(length 3.81)
					(name "14"
						(effects
							(font
								(size 1.27 1.27)
							)
						)
					)
					(number "14"
						(effects
							(font
								(size 1.27 1.27)
							)
						)
					)
				)
				(pin passive line
					(at 22.86 -17.78 180)
					(length 3.81)
					(name "16"
						(effects
							(font
								(size 1.27 1.27)
							)
						)
					)
					(number "16"
						(effects
							(font
								(size 1.27 1.27)
							)
						)
					)
				)
				(pin passive line
					(at 22.86 -20.32 180)
					(length 3.81)
					(name "18"
						(effects
							(font
								(size 1.27 1.27)
							)
						)
					)
					(number "18"
						(effects
							(font
								(size 1.27 1.27)
							)
						)
					)
				)
				(pin passive line
					(at 22.86 -22.86 180)
					(length 3.81)
					(name "20"
						(effects
							(font
								(size 1.27 1.27)
							)
						)
					)
					(number "20"
						(effects
							(font
								(size 1.27 1.27)
							)
						)
					)
				)
				(pin passive line
					(at 22.86 -25.4 180)
					(length 3.81)
					(name "22"
						(effects
							(font
								(size 1.27 1.27)
							)
						)
					)
					(number "22"
						(effects
							(font
								(size 1.27 1.27)
							)
						)
					)
				)
				(pin passive line
					(at 22.86 -27.94 180)
					(length 3.81)
					(name "24"
						(effects
							(font
								(size 1.27 1.27)
							)
						)
					)
					(number "24"
						(effects
							(font
								(size 1.27 1.27)
							)
						)
					)
				)
				(pin passive line
					(at 22.86 -30.48 180)
					(length 3.81)
					(name "26"
						(effects
							(font
								(size 1.27 1.27)
							)
						)
					)
					(number "26"
						(effects
							(font
								(size 1.27 1.27)
							)
						)
					)
				)
				(pin passive line
					(at 22.86 -33.02 180)
					(length 3.81)
					(name "28"
						(effects
							(font
								(size 1.27 1.27)
							)
						)
					)
					(number "28"
						(effects
							(font
								(size 1.27 1.27)
							)
						)
					)
				)
				(pin passive line
					(at 22.86 -35.56 180)
					(length 3.81)
					(name "30"
						(effects
							(font
								(size 1.27 1.27)
							)
						)
					)
					(number "30"
						(effects
							(font
								(size 1.27 1.27)
							)
						)
					)
				)
				(pin passive line
					(at 22.86 -38.1 180)
					(length 3.81)
					(name "32"
						(effects
							(font
								(size 1.27 1.27)
							)
						)
					)
					(number "32"
						(effects
							(font
								(size 1.27 1.27)
							)
						)
					)
				)
				(pin passive line
					(at 22.86 -40.64 180)
					(length 3.81)
					(name "34"
						(effects
							(font
								(size 1.27 1.27)
							)
						)
					)
					(number "34"
						(effects
							(font
								(size 1.27 1.27)
							)
						)
					)
				)
				(pin passive line
					(at 22.86 -43.18 180)
					(length 3.81)
					(name "36"
						(effects
							(font
								(size 1.27 1.27)
							)
						)
					)
					(number "36"
						(effects
							(font
								(size 1.27 1.27)
							)
						)
					)
				)
				(pin passive line
					(at 22.86 -45.72 180)
					(length 3.81)
					(name "38"
						(effects
							(font
								(size 1.27 1.27)
							)
						)
					)
					(number "38"
						(effects
							(font
								(size 1.27 1.27)
							)
						)
					)
				)
				(pin passive line
					(at 22.86 -48.26 180)
					(length 3.81)
					(name "40"
						(effects
							(font
								(size 1.27 1.27)
							)
						)
					)
					(number "40"
						(effects
							(font
								(size 1.27 1.27)
							)
						)
					)
				)
				(pin passive line
					(at 22.86 -50.8 180)
					(length 3.81)
					(name "42"
						(effects
							(font
								(size 1.27 1.27)
							)
						)
					)
					(number "42"
						(effects
							(font
								(size 1.27 1.27)
							)
						)
					)
				)
				(pin passive line
					(at 22.86 -53.34 180)
					(length 3.81)
					(name "44"
						(effects
							(font
								(size 1.27 1.27)
							)
						)
					)
					(number "44"
						(effects
							(font
								(size 1.27 1.27)
							)
						)
					)
				)
				(pin passive line
					(at 22.86 -55.88 180)
					(length 3.81)
					(name "46"
						(effects
							(font
								(size 1.27 1.27)
							)
						)
					)
					(number "46"
						(effects
							(font
								(size 1.27 1.27)
							)
						)
					)
				)
				(pin passive line
					(at 22.86 -58.42 180)
					(length 3.81)
					(name "48"
						(effects
							(font
								(size 1.27 1.27)
							)
						)
					)
					(number "48"
						(effects
							(font
								(size 1.27 1.27)
							)
						)
					)
				)
				(pin passive line
					(at 22.86 -60.96 180)
					(length 3.81)
					(name "50"
						(effects
							(font
								(size 1.27 1.27)
							)
						)
					)
					(number "50"
						(effects
							(font
								(size 1.27 1.27)
							)
						)
					)
				)
				(pin passive line
					(at 22.86 -63.5 180)
					(length 3.81)
					(name "52"
						(effects
							(font
								(size 1.27 1.27)
							)
						)
					)
					(number "52"
						(effects
							(font
								(size 1.27 1.27)
							)
						)
					)
				)
				(pin passive line
					(at 22.86 -66.04 180)
					(length 3.81)
					(name "54"
						(effects
							(font
								(size 1.27 1.27)
							)
						)
					)
					(number "54"
						(effects
							(font
								(size 1.27 1.27)
							)
						)
					)
				)
				(pin passive line
					(at 22.86 -68.58 180)
					(length 3.81)
					(name "56"
						(effects
							(font
								(size 1.27 1.27)
							)
						)
					)
					(number "56"
						(effects
							(font
								(size 1.27 1.27)
							)
						)
					)
				)
				(pin passive line
					(at 22.86 -71.12 180)
					(length 3.81)
					(name "58"
						(effects
							(font
								(size 1.27 1.27)
							)
						)
					)
					(number "58"
						(effects
							(font
								(size 1.27 1.27)
							)
						)
					)
				)
				(pin passive line
					(at 22.86 -73.66 180)
					(length 3.81)
					(name "60"
						(effects
							(font
								(size 1.27 1.27)
							)
						)
					)
					(number "60"
						(effects
							(font
								(size 1.27 1.27)
							)
						)
					)
				)
				(pin passive line
					(at 22.86 -76.2 180)
					(length 3.81)
					(name "62"
						(effects
							(font
								(size 1.27 1.27)
							)
						)
					)
					(number "62"
						(effects
							(font
								(size 1.27 1.27)
							)
						)
					)
				)
				(pin passive line
					(at 22.86 -78.74 180)
					(length 3.81)
					(name "64"
						(effects
							(font
								(size 1.27 1.27)
							)
						)
					)
					(number "64"
						(effects
							(font
								(size 1.27 1.27)
							)
						)
					)
				)
				(pin passive line
					(at 22.86 -81.28 180)
					(length 3.81)
					(name "66"
						(effects
							(font
								(size 1.27 1.27)
							)
						)
					)
					(number "66"
						(effects
							(font
								(size 1.27 1.27)
							)
						)
					)
				)
				(pin passive line
					(at 22.86 -83.82 180)
					(length 3.81)
					(name "68"
						(effects
							(font
								(size 1.27 1.27)
							)
						)
					)
					(number "68"
						(effects
							(font
								(size 1.27 1.27)
							)
						)
					)
				)
				(pin passive line
					(at 22.86 -86.36 180)
					(length 3.81)
					(name "70"
						(effects
							(font
								(size 1.27 1.27)
							)
						)
					)
					(number "70"
						(effects
							(font
								(size 1.27 1.27)
							)
						)
					)
				)
				(pin passive line
					(at 22.86 -88.9 180)
					(length 3.81)
					(name "72"
						(effects
							(font
								(size 1.27 1.27)
							)
						)
					)
					(number "72"
						(effects
							(font
								(size 1.27 1.27)
							)
						)
					)
				)
				(pin passive line
					(at 22.86 -91.44 180)
					(length 3.81)
					(name "74"
						(effects
							(font
								(size 1.27 1.27)
							)
						)
					)
					(number "74"
						(effects
							(font
								(size 1.27 1.27)
							)
						)
					)
				)
				(pin passive line
					(at 22.86 -93.98 180)
					(length 3.81)
					(name "76"
						(effects
							(font
								(size 1.27 1.27)
							)
						)
					)
					(number "76"
						(effects
							(font
								(size 1.27 1.27)
							)
						)
					)
				)
				(pin passive line
					(at 22.86 -96.52 180)
					(length 3.81)
					(name "78"
						(effects
							(font
								(size 1.27 1.27)
							)
						)
					)
					(number "78"
						(effects
							(font
								(size 1.27 1.27)
							)
						)
					)
				)
				(pin passive line
					(at 22.86 -99.06 180)
					(length 3.81)
					(name "80"
						(effects
							(font
								(size 1.27 1.27)
							)
						)
					)
					(number "80"
						(effects
							(font
								(size 1.27 1.27)
							)
						)
					)
				)
				(pin passive line
					(at 22.86 -101.6 180)
					(length 3.81)
					(name "82"
						(effects
							(font
								(size 1.27 1.27)
							)
						)
					)
					(number "82"
						(effects
							(font
								(size 1.27 1.27)
							)
						)
					)
				)
				(pin passive line
					(at 22.86 -104.14 180)
					(length 3.81)
					(name "84"
						(effects
							(font
								(size 1.27 1.27)
							)
						)
					)
					(number "84"
						(effects
							(font
								(size 1.27 1.27)
							)
						)
					)
				)
				(pin passive line
					(at 22.86 -106.68 180)
					(length 3.81)
					(name "86"
						(effects
							(font
								(size 1.27 1.27)
							)
						)
					)
					(number "86"
						(effects
							(font
								(size 1.27 1.27)
							)
						)
					)
				)
				(pin passive line
					(at 22.86 -109.22 180)
					(length 3.81)
					(name "88"
						(effects
							(font
								(size 1.27 1.27)
							)
						)
					)
					(number "88"
						(effects
							(font
								(size 1.27 1.27)
							)
						)
					)
				)
				(pin passive line
					(at 22.86 -111.76 180)
					(length 3.81)
					(name "90"
						(effects
							(font
								(size 1.27 1.27)
							)
						)
					)
					(number "90"
						(effects
							(font
								(size 1.27 1.27)
							)
						)
					)
				)
				(pin passive line
					(at 22.86 -114.3 180)
					(length 3.81)
					(name "92"
						(effects
							(font
								(size 1.27 1.27)
							)
						)
					)
					(number "92"
						(effects
							(font
								(size 1.27 1.27)
							)
						)
					)
				)
				(pin passive line
					(at 22.86 -116.84 180)
					(length 3.81)
					(name "94"
						(effects
							(font
								(size 1.27 1.27)
							)
						)
					)
					(number "94"
						(effects
							(font
								(size 1.27 1.27)
							)
						)
					)
				)
				(pin passive line
					(at 22.86 -119.38 180)
					(length 3.81)
					(name "96"
						(effects
							(font
								(size 1.27 1.27)
							)
						)
					)
					(number "96"
						(effects
							(font
								(size 1.27 1.27)
							)
						)
					)
				)
				(pin passive line
					(at 22.86 -121.92 180)
					(length 3.81)
					(name "98"
						(effects
							(font
								(size 1.27 1.27)
							)
						)
					)
					(number "98"
						(effects
							(font
								(size 1.27 1.27)
							)
						)
					)
				)
				(pin passive line
					(at 22.86 -124.46 180)
					(length 3.81)
					(name "100"
						(effects
							(font
								(size 1.27 1.27)
							)
						)
					)
					(number "100"
						(effects
							(font
								(size 1.27 1.27)
							)
						)
					)
				)
				(pin passive line
					(at 22.86 -127 180)
					(length 3.81)
					(name "102"
						(effects
							(font
								(size 1.27 1.27)
							)
						)
					)
					(number "102"
						(effects
							(font
								(size 1.27 1.27)
							)
						)
					)
				)
				(pin passive line
					(at 22.86 -129.54 180)
					(length 3.81)
					(name "104"
						(effects
							(font
								(size 1.27 1.27)
							)
						)
					)
					(number "104"
						(effects
							(font
								(size 1.27 1.27)
							)
						)
					)
				)
				(pin passive line
					(at 22.86 -132.08 180)
					(length 3.81)
					(name "106"
						(effects
							(font
								(size 1.27 1.27)
							)
						)
					)
					(number "106"
						(effects
							(font
								(size 1.27 1.27)
							)
						)
					)
				)
				(pin passive line
					(at 22.86 -134.62 180)
					(length 3.81)
					(name "108"
						(effects
							(font
								(size 1.27 1.27)
							)
						)
					)
					(number "108"
						(effects
							(font
								(size 1.27 1.27)
							)
						)
					)
				)
				(pin passive line
					(at 22.86 -137.16 180)
					(length 3.81)
					(name "110"
						(effects
							(font
								(size 1.27 1.27)
							)
						)
					)
					(number "110"
						(effects
							(font
								(size 1.27 1.27)
							)
						)
					)
				)
				(pin passive line
					(at 22.86 -139.7 180)
					(length 3.81)
					(name "112"
						(effects
							(font
								(size 1.27 1.27)
							)
						)
					)
					(number "112"
						(effects
							(font
								(size 1.27 1.27)
							)
						)
					)
				)
				(pin passive line
					(at 22.86 -142.24 180)
					(length 3.81)
					(name "114"
						(effects
							(font
								(size 1.27 1.27)
							)
						)
					)
					(number "114"
						(effects
							(font
								(size 1.27 1.27)
							)
						)
					)
				)
				(pin passive line
					(at 22.86 -144.78 180)
					(length 3.81)
					(name "116"
						(effects
							(font
								(size 1.27 1.27)
							)
						)
					)
					(number "116"
						(effects
							(font
								(size 1.27 1.27)
							)
						)
					)
				)
				(pin passive line
					(at 22.86 -147.32 180)
					(length 3.81)
					(name "118"
						(effects
							(font
								(size 1.27 1.27)
							)
						)
					)
					(number "118"
						(effects
							(font
								(size 1.27 1.27)
							)
						)
					)
				)
				(pin passive line
					(at 22.86 -149.86 180)
					(length 3.81)
					(name "120"
						(effects
							(font
								(size 1.27 1.27)
							)
						)
					)
					(number "120"
						(effects
							(font
								(size 1.27 1.27)
							)
						)
					)
				)
				(pin passive line
					(at 22.86 -152.4 180)
					(length 3.81)
					(name "122"
						(effects
							(font
								(size 1.27 1.27)
							)
						)
					)
					(number "122"
						(effects
							(font
								(size 1.27 1.27)
							)
						)
					)
				)
				(pin passive line
					(at 22.86 -154.94 180)
					(length 3.81)
					(name "124"
						(effects
							(font
								(size 1.27 1.27)
							)
						)
					)
					(number "124"
						(effects
							(font
								(size 1.27 1.27)
							)
						)
					)
				)
				(pin passive line
					(at 22.86 -157.48 180)
					(length 3.81)
					(name "126"
						(effects
							(font
								(size 1.27 1.27)
							)
						)
					)
					(number "126"
						(effects
							(font
								(size 1.27 1.27)
							)
						)
					)
				)
				(pin passive line
					(at 22.86 -160.02 180)
					(length 3.81)
					(name "128"
						(effects
							(font
								(size 1.27 1.27)
							)
						)
					)
					(number "128"
						(effects
							(font
								(size 1.27 1.27)
							)
						)
					)
				)
				(pin passive line
					(at 22.86 -162.56 180)
					(length 3.81)
					(name "130"
						(effects
							(font
								(size 1.27 1.27)
							)
						)
					)
					(number "130"
						(effects
							(font
								(size 1.27 1.27)
							)
						)
					)
				)
			)
			(symbol "Edge_Conn_Bus_DDR4_2_1"
				(rectangle
					(start 3.81 2.54)
					(end 19.05 -165.1)
					(stroke
						(width 0.254)
						(type default)
					)
					(fill
						(type background)
					)
				)
				(polyline
					(pts
						(xy 3.81 -165.1) (xy 19.05 -165.1)
					)
					(stroke
						(width 0.254)
						(type default)
					)
					(fill
						(type background)
					)
				)
				(pin passive line
					(at 0 0 0)
					(length 3.81)
					(name "131"
						(effects
							(font
								(size 1.27 1.27)
							)
						)
					)
					(number "131"
						(effects
							(font
								(size 1.27 1.27)
							)
						)
					)
				)
				(pin passive line
					(at 0 -2.54 0)
					(length 3.81)
					(name "133"
						(effects
							(font
								(size 1.27 1.27)
							)
						)
					)
					(number "133"
						(effects
							(font
								(size 1.27 1.27)
							)
						)
					)
				)
				(pin passive line
					(at 0 -5.08 0)
					(length 3.81)
					(name "135"
						(effects
							(font
								(size 1.27 1.27)
							)
						)
					)
					(number "135"
						(effects
							(font
								(size 1.27 1.27)
							)
						)
					)
				)
				(pin passive line
					(at 0 -7.62 0)
					(length 3.81)
					(name "137"
						(effects
							(font
								(size 1.27 1.27)
							)
						)
					)
					(number "137"
						(effects
							(font
								(size 1.27 1.27)
							)
						)
					)
				)
				(pin passive line
					(at 0 -10.16 0)
					(length 3.81)
					(name "139"
						(effects
							(font
								(size 1.27 1.27)
							)
						)
					)
					(number "139"
						(effects
							(font
								(size 1.27 1.27)
							)
						)
					)
				)
				(pin passive line
					(at 0 -12.7 0)
					(length 3.81)
					(name "141"
						(effects
							(font
								(size 1.27 1.27)
							)
						)
					)
					(number "141"
						(effects
							(font
								(size 1.27 1.27)
							)
						)
					)
				)
				(pin passive line
					(at 0 -15.24 0)
					(length 3.81)
					(name "143"
						(effects
							(font
								(size 1.27 1.27)
							)
						)
					)
					(number "143"
						(effects
							(font
								(size 1.27 1.27)
							)
						)
					)
				)
				(pin passive line
					(at 0 -17.78 0)
					(length 3.81)
					(name "145"
						(effects
							(font
								(size 1.27 1.27)
							)
						)
					)
					(number "145"
						(effects
							(font
								(size 1.27 1.27)
							)
						)
					)
				)
				(pin passive line
					(at 0 -20.32 0)
					(length 3.81)
					(name "147"
						(effects
							(font
								(size 1.27 1.27)
							)
						)
					)
					(number "147"
						(effects
							(font
								(size 1.27 1.27)
							)
						)
					)
				)
				(pin passive line
					(at 0 -22.86 0)
					(length 3.81)
					(name "149"
						(effects
							(font
								(size 1.27 1.27)
							)
						)
					)
					(number "149"
						(effects
							(font
								(size 1.27 1.27)
							)
						)
					)
				)
				(pin passive line
					(at 0 -25.4 0)
					(length 3.81)
					(name "151"
						(effects
							(font
								(size 1.27 1.27)
							)
						)
					)
					(number "151"
						(effects
							(font
								(size 1.27 1.27)
							)
						)
					)
				)
				(pin passive line
					(at 0 -27.94 0)
					(length 3.81)
					(name "153"
						(effects
							(font
								(size 1.27 1.27)
							)
						)
					)
					(number "153"
						(effects
							(font
								(size 1.27 1.27)
							)
						)
					)
				)
				(pin passive line
					(at 0 -30.48 0)
					(length 3.81)
					(name "155"
						(effects
							(font
								(size 1.27 1.27)
							)
						)
					)
					(number "155"
						(effects
							(font
								(size 1.27 1.27)
							)
						)
					)
				)
				(pin passive line
					(at 0 -33.02 0)
					(length 3.81)
					(name "157"
						(effects
							(font
								(size 1.27 1.27)
							)
						)
					)
					(number "157"
						(effects
							(font
								(size 1.27 1.27)
							)
						)
					)
				)
				(pin passive line
					(at 0 -35.56 0)
					(length 3.81)
					(name "159"
						(effects
							(font
								(size 1.27 1.27)
							)
						)
					)
					(number "159"
						(effects
							(font
								(size 1.27 1.27)
							)
						)
					)
				)
				(pin passive line
					(at 0 -38.1 0)
					(length 3.81)
					(name "161"
						(effects
							(font
								(size 1.27 1.27)
							)
						)
					)
					(number "161"
						(effects
							(font
								(size 1.27 1.27)
							)
						)
					)
				)
				(pin passive line
					(at 0 -40.64 0)
					(length 3.81)
					(name "163"
						(effects
							(font
								(size 1.27 1.27)
							)
						)
					)
					(number "163"
						(effects
							(font
								(size 1.27 1.27)
							)
						)
					)
				)
				(pin passive line
					(at 0 -43.18 0)
					(length 3.81)
					(name "165"
						(effects
							(font
								(size 1.27 1.27)
							)
						)
					)
					(number "165"
						(effects
							(font
								(size 1.27 1.27)
							)
						)
					)
				)
				(pin passive line
					(at 0 -45.72 0)
					(length 3.81)
					(name "167"
						(effects
							(font
								(size 1.27 1.27)
							)
						)
					)
					(number "167"
						(effects
							(font
								(size 1.27 1.27)
							)
						)
					)
				)
				(pin passive line
					(at 0 -48.26 0)
					(length 3.81)
					(name "169"
						(effects
							(font
								(size 1.27 1.27)
							)
						)
					)
					(number "169"
						(effects
							(font
								(size 1.27 1.27)
							)
						)
					)
				)
				(pin passive line
					(at 0 -50.8 0)
					(length 3.81)
					(name "171"
						(effects
							(font
								(size 1.27 1.27)
							)
						)
					)
					(number "171"
						(effects
							(font
								(size 1.27 1.27)
							)
						)
					)
				)
				(pin passive line
					(at 0 -53.34 0)
					(length 3.81)
					(name "173"
						(effects
							(font
								(size 1.27 1.27)
							)
						)
					)
					(number "173"
						(effects
							(font
								(size 1.27 1.27)
							)
						)
					)
				)
				(pin passive line
					(at 0 -55.88 0)
					(length 3.81)
					(name "175"
						(effects
							(font
								(size 1.27 1.27)
							)
						)
					)
					(number "175"
						(effects
							(font
								(size 1.27 1.27)
							)
						)
					)
				)
				(pin passive line
					(at 0 -58.42 0)
					(length 3.81)
					(name "177"
						(effects
							(font
								(size 1.27 1.27)
							)
						)
					)
					(number "177"
						(effects
							(font
								(size 1.27 1.27)
							)
						)
					)
				)
				(pin passive line
					(at 0 -60.96 0)
					(length 3.81)
					(name "179"
						(effects
							(font
								(size 1.27 1.27)
							)
						)
					)
					(number "179"
						(effects
							(font
								(size 1.27 1.27)
							)
						)
					)
				)
				(pin passive line
					(at 0 -63.5 0)
					(length 3.81)
					(name "181"
						(effects
							(font
								(size 1.27 1.27)
							)
						)
					)
					(number "181"
						(effects
							(font
								(size 1.27 1.27)
							)
						)
					)
				)
				(pin passive line
					(at 0 -66.04 0)
					(length 3.81)
					(name "183"
						(effects
							(font
								(size 1.27 1.27)
							)
						)
					)
					(number "183"
						(effects
							(font
								(size 1.27 1.27)
							)
						)
					)
				)
				(pin passive line
					(at 0 -68.58 0)
					(length 3.81)
					(name "185"
						(effects
							(font
								(size 1.27 1.27)
							)
						)
					)
					(number "185"
						(effects
							(font
								(size 1.27 1.27)
							)
						)
					)
				)
				(pin passive line
					(at 0 -71.12 0)
					(length 3.81)
					(name "187"
						(effects
							(font
								(size 1.27 1.27)
							)
						)
					)
					(number "187"
						(effects
							(font
								(size 1.27 1.27)
							)
						)
					)
				)
				(pin passive line
					(at 0 -73.66 0)
					(length 3.81)
					(name "189"
						(effects
							(font
								(size 1.27 1.27)
							)
						)
					)
					(number "189"
						(effects
							(font
								(size 1.27 1.27)
							)
						)
					)
				)
				(pin passive line
					(at 0 -76.2 0)
					(length 3.81)
					(name "191"
						(effects
							(font
								(size 1.27 1.27)
							)
						)
					)
					(number "191"
						(effects
							(font
								(size 1.27 1.27)
							)
						)
					)
				)
				(pin passive line
					(at 0 -78.74 0)
					(length 3.81)
					(name "193"
						(effects
							(font
								(size 1.27 1.27)
							)
						)
					)
					(number "193"
						(effects
							(font
								(size 1.27 1.27)
							)
						)
					)
				)
				(pin passive line
					(at 0 -81.28 0)
					(length 3.81)
					(name "195"
						(effects
							(font
								(size 1.27 1.27)
							)
						)
					)
					(number "195"
						(effects
							(font
								(size 1.27 1.27)
							)
						)
					)
				)
				(pin passive line
					(at 0 -83.82 0)
					(length 3.81)
					(name "197"
						(effects
							(font
								(size 1.27 1.27)
							)
						)
					)
					(number "197"
						(effects
							(font
								(size 1.27 1.27)
							)
						)
					)
				)
				(pin passive line
					(at 0 -86.36 0)
					(length 3.81)
					(name "199"
						(effects
							(font
								(size 1.27 1.27)
							)
						)
					)
					(number "199"
						(effects
							(font
								(size 1.27 1.27)
							)
						)
					)
				)
				(pin passive line
					(at 0 -88.9 0)
					(length 3.81)
					(name "201"
						(effects
							(font
								(size 1.27 1.27)
							)
						)
					)
					(number "201"
						(effects
							(font
								(size 1.27 1.27)
							)
						)
					)
				)
				(pin passive line
					(at 0 -91.44 0)
					(length 3.81)
					(name "203"
						(effects
							(font
								(size 1.27 1.27)
							)
						)
					)
					(number "203"
						(effects
							(font
								(size 1.27 1.27)
							)
						)
					)
				)
				(pin passive line
					(at 0 -93.98 0)
					(length 3.81)
					(name "205"
						(effects
							(font
								(size 1.27 1.27)
							)
						)
					)
					(number "205"
						(effects
							(font
								(size 1.27 1.27)
							)
						)
					)
				)
				(pin passive line
					(at 0 -96.52 0)
					(length 3.81)
					(name "207"
						(effects
							(font
								(size 1.27 1.27)
							)
						)
					)
					(number "207"
						(effects
							(font
								(size 1.27 1.27)
							)
						)
					)
				)
				(pin passive line
					(at 0 -99.06 0)
					(length 3.81)
					(name "209"
						(effects
							(font
								(size 1.27 1.27)
							)
						)
					)
					(number "209"
						(effects
							(font
								(size 1.27 1.27)
							)
						)
					)
				)
				(pin passive line
					(at 0 -101.6 0)
					(length 3.81)
					(name "211"
						(effects
							(font
								(size 1.27 1.27)
							)
						)
					)
					(number "211"
						(effects
							(font
								(size 1.27 1.27)
							)
						)
					)
				)
				(pin passive line
					(at 0 -104.14 0)
					(length 3.81)
					(name "213"
						(effects
							(font
								(size 1.27 1.27)
							)
						)
					)
					(number "213"
						(effects
							(font
								(size 1.27 1.27)
							)
						)
					)
				)
				(pin passive line
					(at 0 -106.68 0)
					(length 3.81)
					(name "215"
						(effects
							(font
								(size 1.27 1.27)
							)
						)
					)
					(number "215"
						(effects
							(font
								(size 1.27 1.27)
							)
						)
					)
				)
				(pin passive line
					(at 0 -109.22 0)
					(length 3.81)
					(name "217"
						(effects
							(font
								(size 1.27 1.27)
							)
						)
					)
					(number "217"
						(effects
							(font
								(size 1.27 1.27)
							)
						)
					)
				)
				(pin passive line
					(at 0 -111.76 0)
					(length 3.81)
					(name "219"
						(effects
							(font
								(size 1.27 1.27)
							)
						)
					)
					(number "219"
						(effects
							(font
								(size 1.27 1.27)
							)
						)
					)
				)
				(pin passive line
					(at 0 -114.3 0)
					(length 3.81)
					(name "221"
						(effects
							(font
								(size 1.27 1.27)
							)
						)
					)
					(number "221"
						(effects
							(font
								(size 1.27 1.27)
							)
						)
					)
				)
				(pin passive line
					(at 0 -116.84 0)
					(length 3.81)
					(name "223"
						(effects
							(font
								(size 1.27 1.27)
							)
						)
					)
					(number "223"
						(effects
							(font
								(size 1.27 1.27)
							)
						)
					)
				)
				(pin passive line
					(at 0 -119.38 0)
					(length 3.81)
					(name "225"
						(effects
							(font
								(size 1.27 1.27)
							)
						)
					)
					(number "225"
						(effects
							(font
								(size 1.27 1.27)
							)
						)
					)
				)
				(pin passive line
					(at 0 -121.92 0)
					(length 3.81)
					(name "227"
						(effects
							(font
								(size 1.27 1.27)
							)
						)
					)
					(number "227"
						(effects
							(font
								(size 1.27 1.27)
							)
						)
					)
				)
				(pin passive line
					(at 0 -124.46 0)
					(length 3.81)
					(name "229"
						(effects
							(font
								(size 1.27 1.27)
							)
						)
					)
					(number "229"
						(effects
							(font
								(size 1.27 1.27)
							)
						)
					)
				)
				(pin passive line
					(at 0 -127 0)
					(length 3.81)
					(name "231"
						(effects
							(font
								(size 1.27 1.27)
							)
						)
					)
					(number "231"
						(effects
							(font
								(size 1.27 1.27)
							)
						)
					)
				)
				(pin passive line
					(at 0 -129.54 0)
					(length 3.81)
					(name "233"
						(effects
							(font
								(size 1.27 1.27)
							)
						)
					)
					(number "233"
						(effects
							(font
								(size 1.27 1.27)
							)
						)
					)
				)
				(pin passive line
					(at 0 -132.08 0)
					(length 3.81)
					(name "235"
						(effects
							(font
								(size 1.27 1.27)
							)
						)
					)
					(number "235"
						(effects
							(font
								(size 1.27 1.27)
							)
						)
					)
				)
				(pin passive line
					(at 0 -134.62 0)
					(length 3.81)
					(name "237"
						(effects
							(font
								(size 1.27 1.27)
							)
						)
					)
					(number "237"
						(effects
							(font
								(size 1.27 1.27)
							)
						)
					)
				)
				(pin passive line
					(at 0 -137.16 0)
					(length 3.81)
					(name "239"
						(effects
							(font
								(size 1.27 1.27)
							)
						)
					)
					(number "239"
						(effects
							(font
								(size 1.27 1.27)
							)
						)
					)
				)
				(pin passive line
					(at 0 -139.7 0)
					(length 3.81)
					(name "241"
						(effects
							(font
								(size 1.27 1.27)
							)
						)
					)
					(number "241"
						(effects
							(font
								(size 1.27 1.27)
							)
						)
					)
				)
				(pin passive line
					(at 0 -142.24 0)
					(length 3.81)
					(name "243"
						(effects
							(font
								(size 1.27 1.27)
							)
						)
					)
					(number "243"
						(effects
							(font
								(size 1.27 1.27)
							)
						)
					)
				)
				(pin passive line
					(at 0 -144.78 0)
					(length 3.81)
					(name "245"
						(effects
							(font
								(size 1.27 1.27)
							)
						)
					)
					(number "245"
						(effects
							(font
								(size 1.27 1.27)
							)
						)
					)
				)
				(pin passive line
					(at 0 -147.32 0)
					(length 3.81)
					(name "247"
						(effects
							(font
								(size 1.27 1.27)
							)
						)
					)
					(number "247"
						(effects
							(font
								(size 1.27 1.27)
							)
						)
					)
				)
				(pin passive line
					(at 0 -149.86 0)
					(length 3.81)
					(name "249"
						(effects
							(font
								(size 1.27 1.27)
							)
						)
					)
					(number "249"
						(effects
							(font
								(size 1.27 1.27)
							)
						)
					)
				)
				(pin passive line
					(at 0 -152.4 0)
					(length 3.81)
					(name "251"
						(effects
							(font
								(size 1.27 1.27)
							)
						)
					)
					(number "251"
						(effects
							(font
								(size 1.27 1.27)
							)
						)
					)
				)
				(pin passive line
					(at 0 -154.94 0)
					(length 3.81)
					(name "253"
						(effects
							(font
								(size 1.27 1.27)
							)
						)
					)
					(number "253"
						(effects
							(font
								(size 1.27 1.27)
							)
						)
					)
				)
				(pin passive line
					(at 0 -157.48 0)
					(length 3.81)
					(name "255"
						(effects
							(font
								(size 1.27 1.27)
							)
						)
					)
					(number "255"
						(effects
							(font
								(size 1.27 1.27)
							)
						)
					)
				)
				(pin passive line
					(at 0 -160.02 0)
					(length 3.81)
					(name "257"
						(effects
							(font
								(size 1.27 1.27)
							)
						)
					)
					(number "257"
						(effects
							(font
								(size 1.27 1.27)
							)
						)
					)
				)
				(pin passive line
					(at 0 -162.56 0)
					(length 3.81)
					(name "259"
						(effects
							(font
								(size 1.27 1.27)
							)
						)
					)
					(number "259"
						(effects
							(font
								(size 1.27 1.27)
							)
						)
					)
				)
				(pin passive line
					(at 22.86 0 180)
					(length 3.81)
					(name "132"
						(effects
							(font
								(size 1.27 1.27)
							)
						)
					)
					(number "132"
						(effects
							(font
								(size 1.27 1.27)
							)
						)
					)
				)
				(pin passive line
					(at 22.86 -2.54 180)
					(length 3.81)
					(name "134"
						(effects
							(font
								(size 1.27 1.27)
							)
						)
					)
					(number "134"
						(effects
							(font
								(size 1.27 1.27)
							)
						)
					)
				)
				(pin passive line
					(at 22.86 -5.08 180)
					(length 3.81)
					(name "136"
						(effects
							(font
								(size 1.27 1.27)
							)
						)
					)
					(number "136"
						(effects
							(font
								(size 1.27 1.27)
							)
						)
					)
				)
				(pin passive line
					(at 22.86 -7.62 180)
					(length 3.81)
					(name "138"
						(effects
							(font
								(size 1.27 1.27)
							)
						)
					)
					(number "138"
						(effects
							(font
								(size 1.27 1.27)
							)
						)
					)
				)
				(pin passive line
					(at 22.86 -10.16 180)
					(length 3.81)
					(name "140"
						(effects
							(font
								(size 1.27 1.27)
							)
						)
					)
					(number "140"
						(effects
							(font
								(size 1.27 1.27)
							)
						)
					)
				)
				(pin passive line
					(at 22.86 -12.7 180)
					(length 3.81)
					(name "142"
						(effects
							(font
								(size 1.27 1.27)
							)
						)
					)
					(number "142"
						(effects
							(font
								(size 1.27 1.27)
							)
						)
					)
				)
				(pin passive line
					(at 22.86 -15.24 180)
					(length 3.81)
					(name "144"
						(effects
							(font
								(size 1.27 1.27)
							)
						)
					)
					(number "144"
						(effects
							(font
								(size 1.27 1.27)
							)
						)
					)
				)
				(pin passive line
					(at 22.86 -17.78 180)
					(length 3.81)
					(name "146"
						(effects
							(font
								(size 1.27 1.27)
							)
						)
					)
					(number "146"
						(effects
							(font
								(size 1.27 1.27)
							)
						)
					)
				)
				(pin passive line
					(at 22.86 -20.32 180)
					(length 3.81)
					(name "148"
						(effects
							(font
								(size 1.27 1.27)
							)
						)
					)
					(number "148"
						(effects
							(font
								(size 1.27 1.27)
							)
						)
					)
				)
				(pin passive line
					(at 22.86 -22.86 180)
					(length 3.81)
					(name "150"
						(effects
							(font
								(size 1.27 1.27)
							)
						)
					)
					(number "150"
						(effects
							(font
								(size 1.27 1.27)
							)
						)
					)
				)
				(pin passive line
					(at 22.86 -25.4 180)
					(length 3.81)
					(name "152"
						(effects
							(font
								(size 1.27 1.27)
							)
						)
					)
					(number "152"
						(effects
							(font
								(size 1.27 1.27)
							)
						)
					)
				)
				(pin passive line
					(at 22.86 -27.94 180)
					(length 3.81)
					(name "154"
						(effects
							(font
								(size 1.27 1.27)
							)
						)
					)
					(number "154"
						(effects
							(font
								(size 1.27 1.27)
							)
						)
					)
				)
				(pin passive line
					(at 22.86 -30.48 180)
					(length 3.81)
					(name "156"
						(effects
							(font
								(size 1.27 1.27)
							)
						)
					)
					(number "156"
						(effects
							(font
								(size 1.27 1.27)
							)
						)
					)
				)
				(pin passive line
					(at 22.86 -33.02 180)
					(length 3.81)
					(name "158"
						(effects
							(font
								(size 1.27 1.27)
							)
						)
					)
					(number "158"
						(effects
							(font
								(size 1.27 1.27)
							)
						)
					)
				)
				(pin passive line
					(at 22.86 -35.56 180)
					(length 3.81)
					(name "160"
						(effects
							(font
								(size 1.27 1.27)
							)
						)
					)
					(number "160"
						(effects
							(font
								(size 1.27 1.27)
							)
						)
					)
				)
				(pin passive line
					(at 22.86 -38.1 180)
					(length 3.81)
					(name "162"
						(effects
							(font
								(size 1.27 1.27)
							)
						)
					)
					(number "162"
						(effects
							(font
								(size 1.27 1.27)
							)
						)
					)
				)
				(pin passive line
					(at 22.86 -40.64 180)
					(length 3.81)
					(name "164"
						(effects
							(font
								(size 1.27 1.27)
							)
						)
					)
					(number "164"
						(effects
							(font
								(size 1.27 1.27)
							)
						)
					)
				)
				(pin passive line
					(at 22.86 -43.18 180)
					(length 3.81)
					(name "166"
						(effects
							(font
								(size 1.27 1.27)
							)
						)
					)
					(number "166"
						(effects
							(font
								(size 1.27 1.27)
							)
						)
					)
				)
				(pin passive line
					(at 22.86 -45.72 180)
					(length 3.81)
					(name "168"
						(effects
							(font
								(size 1.27 1.27)
							)
						)
					)
					(number "168"
						(effects
							(font
								(size 1.27 1.27)
							)
						)
					)
				)
				(pin passive line
					(at 22.86 -48.26 180)
					(length 3.81)
					(name "170"
						(effects
							(font
								(size 1.27 1.27)
							)
						)
					)
					(number "170"
						(effects
							(font
								(size 1.27 1.27)
							)
						)
					)
				)
				(pin passive line
					(at 22.86 -50.8 180)
					(length 3.81)
					(name "172"
						(effects
							(font
								(size 1.27 1.27)
							)
						)
					)
					(number "172"
						(effects
							(font
								(size 1.27 1.27)
							)
						)
					)
				)
				(pin passive line
					(at 22.86 -53.34 180)
					(length 3.81)
					(name "174"
						(effects
							(font
								(size 1.27 1.27)
							)
						)
					)
					(number "174"
						(effects
							(font
								(size 1.27 1.27)
							)
						)
					)
				)
				(pin passive line
					(at 22.86 -55.88 180)
					(length 3.81)
					(name "176"
						(effects
							(font
								(size 1.27 1.27)
							)
						)
					)
					(number "176"
						(effects
							(font
								(size 1.27 1.27)
							)
						)
					)
				)
				(pin passive line
					(at 22.86 -58.42 180)
					(length 3.81)
					(name "178"
						(effects
							(font
								(size 1.27 1.27)
							)
						)
					)
					(number "178"
						(effects
							(font
								(size 1.27 1.27)
							)
						)
					)
				)
				(pin passive line
					(at 22.86 -60.96 180)
					(length 3.81)
					(name "180"
						(effects
							(font
								(size 1.27 1.27)
							)
						)
					)
					(number "180"
						(effects
							(font
								(size 1.27 1.27)
							)
						)
					)
				)
				(pin passive line
					(at 22.86 -63.5 180)
					(length 3.81)
					(name "182"
						(effects
							(font
								(size 1.27 1.27)
							)
						)
					)
					(number "182"
						(effects
							(font
								(size 1.27 1.27)
							)
						)
					)
				)
				(pin passive line
					(at 22.86 -66.04 180)
					(length 3.81)
					(name "184"
						(effects
							(font
								(size 1.27 1.27)
							)
						)
					)
					(number "184"
						(effects
							(font
								(size 1.27 1.27)
							)
						)
					)
				)
				(pin passive line
					(at 22.86 -68.58 180)
					(length 3.81)
					(name "186"
						(effects
							(font
								(size 1.27 1.27)
							)
						)
					)
					(number "186"
						(effects
							(font
								(size 1.27 1.27)
							)
						)
					)
				)
				(pin passive line
					(at 22.86 -71.12 180)
					(length 3.81)
					(name "188"
						(effects
							(font
								(size 1.27 1.27)
							)
						)
					)
					(number "188"
						(effects
							(font
								(size 1.27 1.27)
							)
						)
					)
				)
				(pin passive line
					(at 22.86 -73.66 180)
					(length 3.81)
					(name "190"
						(effects
							(font
								(size 1.27 1.27)
							)
						)
					)
					(number "190"
						(effects
							(font
								(size 1.27 1.27)
							)
						)
					)
				)
				(pin passive line
					(at 22.86 -76.2 180)
					(length 3.81)
					(name "192"
						(effects
							(font
								(size 1.27 1.27)
							)
						)
					)
					(number "192"
						(effects
							(font
								(size 1.27 1.27)
							)
						)
					)
				)
				(pin passive line
					(at 22.86 -78.74 180)
					(length 3.81)
					(name "194"
						(effects
							(font
								(size 1.27 1.27)
							)
						)
					)
					(number "194"
						(effects
							(font
								(size 1.27 1.27)
							)
						)
					)
				)
				(pin passive line
					(at 22.86 -81.28 180)
					(length 3.81)
					(name "196"
						(effects
							(font
								(size 1.27 1.27)
							)
						)
					)
					(number "196"
						(effects
							(font
								(size 1.27 1.27)
							)
						)
					)
				)
				(pin passive line
					(at 22.86 -83.82 180)
					(length 3.81)
					(name "198"
						(effects
							(font
								(size 1.27 1.27)
							)
						)
					)
					(number "198"
						(effects
							(font
								(size 1.27 1.27)
							)
						)
					)
				)
				(pin passive line
					(at 22.86 -86.36 180)
					(length 3.81)
					(name "200"
						(effects
							(font
								(size 1.27 1.27)
							)
						)
					)
					(number "200"
						(effects
							(font
								(size 1.27 1.27)
							)
						)
					)
				)
				(pin passive line
					(at 22.86 -88.9 180)
					(length 3.81)
					(name "202"
						(effects
							(font
								(size 1.27 1.27)
							)
						)
					)
					(number "202"
						(effects
							(font
								(size 1.27 1.27)
							)
						)
					)
				)
				(pin passive line
					(at 22.86 -91.44 180)
					(length 3.81)
					(name "204"
						(effects
							(font
								(size 1.27 1.27)
							)
						)
					)
					(number "204"
						(effects
							(font
								(size 1.27 1.27)
							)
						)
					)
				)
				(pin passive line
					(at 22.86 -93.98 180)
					(length 3.81)
					(name "206"
						(effects
							(font
								(size 1.27 1.27)
							)
						)
					)
					(number "206"
						(effects
							(font
								(size 1.27 1.27)
							)
						)
					)
				)
				(pin passive line
					(at 22.86 -96.52 180)
					(length 3.81)
					(name "208"
						(effects
							(font
								(size 1.27 1.27)
							)
						)
					)
					(number "208"
						(effects
							(font
								(size 1.27 1.27)
							)
						)
					)
				)
				(pin passive line
					(at 22.86 -99.06 180)
					(length 3.81)
					(name "210"
						(effects
							(font
								(size 1.27 1.27)
							)
						)
					)
					(number "210"
						(effects
							(font
								(size 1.27 1.27)
							)
						)
					)
				)
				(pin passive line
					(at 22.86 -101.6 180)
					(length 3.81)
					(name "212"
						(effects
							(font
								(size 1.27 1.27)
							)
						)
					)
					(number "212"
						(effects
							(font
								(size 1.27 1.27)
							)
						)
					)
				)
				(pin passive line
					(at 22.86 -104.14 180)
					(length 3.81)
					(name "214"
						(effects
							(font
								(size 1.27 1.27)
							)
						)
					)
					(number "214"
						(effects
							(font
								(size 1.27 1.27)
							)
						)
					)
				)
				(pin passive line
					(at 22.86 -106.68 180)
					(length 3.81)
					(name "216"
						(effects
							(font
								(size 1.27 1.27)
							)
						)
					)
					(number "216"
						(effects
							(font
								(size 1.27 1.27)
							)
						)
					)
				)
				(pin passive line
					(at 22.86 -109.22 180)
					(length 3.81)
					(name "218"
						(effects
							(font
								(size 1.27 1.27)
							)
						)
					)
					(number "218"
						(effects
							(font
								(size 1.27 1.27)
							)
						)
					)
				)
				(pin passive line
					(at 22.86 -111.76 180)
					(length 3.81)
					(name "220"
						(effects
							(font
								(size 1.27 1.27)
							)
						)
					)
					(number "220"
						(effects
							(font
								(size 1.27 1.27)
							)
						)
					)
				)
				(pin passive line
					(at 22.86 -114.3 180)
					(length 3.81)
					(name "222"
						(effects
							(font
								(size 1.27 1.27)
							)
						)
					)
					(number "222"
						(effects
							(font
								(size 1.27 1.27)
							)
						)
					)
				)
				(pin passive line
					(at 22.86 -116.84 180)
					(length 3.81)
					(name "224"
						(effects
							(font
								(size 1.27 1.27)
							)
						)
					)
					(number "224"
						(effects
							(font
								(size 1.27 1.27)
							)
						)
					)
				)
				(pin passive line
					(at 22.86 -119.38 180)
					(length 3.81)
					(name "226"
						(effects
							(font
								(size 1.27 1.27)
							)
						)
					)
					(number "226"
						(effects
							(font
								(size 1.27 1.27)
							)
						)
					)
				)
				(pin passive line
					(at 22.86 -121.92 180)
					(length 3.81)
					(name "228"
						(effects
							(font
								(size 1.27 1.27)
							)
						)
					)
					(number "228"
						(effects
							(font
								(size 1.27 1.27)
							)
						)
					)
				)
				(pin passive line
					(at 22.86 -124.46 180)
					(length 3.81)
					(name "230"
						(effects
							(font
								(size 1.27 1.27)
							)
						)
					)
					(number "230"
						(effects
							(font
								(size 1.27 1.27)
							)
						)
					)
				)
				(pin passive line
					(at 22.86 -127 180)
					(length 3.81)
					(name "232"
						(effects
							(font
								(size 1.27 1.27)
							)
						)
					)
					(number "232"
						(effects
							(font
								(size 1.27 1.27)
							)
						)
					)
				)
				(pin passive line
					(at 22.86 -129.54 180)
					(length 3.81)
					(name "234"
						(effects
							(font
								(size 1.27 1.27)
							)
						)
					)
					(number "234"
						(effects
							(font
								(size 1.27 1.27)
							)
						)
					)
				)
				(pin passive line
					(at 22.86 -132.08 180)
					(length 3.81)
					(name "236"
						(effects
							(font
								(size 1.27 1.27)
							)
						)
					)
					(number "236"
						(effects
							(font
								(size 1.27 1.27)
							)
						)
					)
				)
				(pin passive line
					(at 22.86 -134.62 180)
					(length 3.81)
					(name "238"
						(effects
							(font
								(size 1.27 1.27)
							)
						)
					)
					(number "238"
						(effects
							(font
								(size 1.27 1.27)
							)
						)
					)
				)
				(pin passive line
					(at 22.86 -137.16 180)
					(length 3.81)
					(name "240"
						(effects
							(font
								(size 1.27 1.27)
							)
						)
					)
					(number "240"
						(effects
							(font
								(size 1.27 1.27)
							)
						)
					)
				)
				(pin passive line
					(at 22.86 -139.7 180)
					(length 3.81)
					(name "242"
						(effects
							(font
								(size 1.27 1.27)
							)
						)
					)
					(number "242"
						(effects
							(font
								(size 1.27 1.27)
							)
						)
					)
				)
				(pin passive line
					(at 22.86 -142.24 180)
					(length 3.81)
					(name "244"
						(effects
							(font
								(size 1.27 1.27)
							)
						)
					)
					(number "244"
						(effects
							(font
								(size 1.27 1.27)
							)
						)
					)
				)
				(pin passive line
					(at 22.86 -144.78 180)
					(length 3.81)
					(name "246"
						(effects
							(font
								(size 1.27 1.27)
							)
						)
					)
					(number "246"
						(effects
							(font
								(size 1.27 1.27)
							)
						)
					)
				)
				(pin passive line
					(at 22.86 -147.32 180)
					(length 3.81)
					(name "248"
						(effects
							(font
								(size 1.27 1.27)
							)
						)
					)
					(number "248"
						(effects
							(font
								(size 1.27 1.27)
							)
						)
					)
				)
				(pin passive line
					(at 22.86 -149.86 180)
					(length 3.81)
					(name "250"
						(effects
							(font
								(size 1.27 1.27)
							)
						)
					)
					(number "250"
						(effects
							(font
								(size 1.27 1.27)
							)
						)
					)
				)
				(pin passive line
					(at 22.86 -152.4 180)
					(length 3.81)
					(name "252"
						(effects
							(font
								(size 1.27 1.27)
							)
						)
					)
					(number "252"
						(effects
							(font
								(size 1.27 1.27)
							)
						)
					)
				)
				(pin passive line
					(at 22.86 -154.94 180)
					(length 3.81)
					(name "254"
						(effects
							(font
								(size 1.27 1.27)
							)
						)
					)
					(number "254"
						(effects
							(font
								(size 1.27 1.27)
							)
						)
					)
				)
				(pin passive line
					(at 22.86 -157.48 180)
					(length 3.81)
					(name "256"
						(effects
							(font
								(size 1.27 1.27)
							)
						)
					)
					(number "256"
						(effects
							(font
								(size 1.27 1.27)
							)
						)
					)
				)
				(pin passive line
					(at 22.86 -160.02 180)
					(length 3.81)
					(name "258"
						(effects
							(font
								(size 1.27 1.27)
							)
						)
					)
					(number "258"
						(effects
							(font
								(size 1.27 1.27)
							)
						)
					)
				)
				(pin passive line
					(at 22.86 -162.56 180)
					(length 3.81)
					(name "260"
						(effects
							(font
								(size 1.27 1.27)
							)
						)
					)
					(number "260"
						(effects
							(font
								(size 1.27 1.27)
							)
						)
					)
				)
			)
		)
)
